FILE_TYPE = MACRO_DRAWING;
SET COLOR_WIRE YELLOW;
SET COLOR_PROP ORANGE;
SET COLOR_DOT WHITE;
SET COLOR_ARC YELLOW;
SET COLOR_BODY GREEN;
SET COLOR_NOTE PURPLE;
SET PROP_DISPLAY VALUE;
SET PAGE_NUMBER P53;
FORCEADD OFFPAGE..2
R 2
(-1700 -175);
FORCEPROP 2 LAST $XR1 103 
J 0
(-2075 -175);
DISPLAY 0.638298 (-2075 -175);
PAINT MONO (-2075 -175);
FORCEPROP 2 LAST $XR0 102 
J 0
(-1955 -175);
DISPLAY 0.638298 (-1955 -175);
PAINT MONO (-1955 -175);
FORCEPROP 2 LAST CDS_LIB standard
J 0
(-1700 -175);
PAINT MONO (-1700 -175);
DISPLAY INVISIBLE (-1700 -175);
FORCEPROP 1 LAST OFFPAGE TRUE
J 2
(-2025 -300);
DISPLAY 0.872340 (-2025 -300);
DISPLAY INVISIBLE (-2025 -300);
FORCEPROP 1 LAST COMMENT_BODY TRUE
J 2
(-1655 -270);
DISPLAY 0.872340 (-1655 -270);
PAINT GREEN (-1655 -270);
DISPLAY INVISIBLE (-1655 -270);
FORCEPROP 2 LAST PATH I1
J 0
(-1650 -100);
DISPLAY 1.021277 (-1650 -100);
DISPLAY INVISIBLE (-1650 -100);
FORCEADD TAP..1
R 2
(-675 50);
FORCEPROP 3 LASTPIN (-625 50) SIG_NAME M_C_CPU1_SB_CB<1>
J 0
(-615 60);
DISPLAY 0.659574 (-615 60);
PAINT MONO (-615 60);
DISPLAY INVISIBLE (-615 60);
FORCEPROP 1 LASTPIN (-625 50) BN 1
J 2
(-613 58);
DISPLAY 0.680851 (-613 58);
PAINT GREEN (-613 58);
FORCEPROP 2 LAST CDS_LIB standard
J 0
(-675 50);
DISPLAY INVISIBLE (-675 50);
FORCEPROP 1 LAST BODY_TYPE PLUMBING
J 2
(-675 100);
DISPLAY 0.872340 (-675 100);
PAINT GREEN (-675 100);
DISPLAY INVISIBLE (-675 100);
FORCEPROP 1 LAST HDL_TAP TRUE
J 2
(-1000 -75);
DISPLAY 0.872340 (-1000 -75);
DISPLAY INVISIBLE (-1000 -75);
FORCEPROP 1 LAST PATH I10
J 2
(-673 50);
DISPLAY 0.872340 (-673 50);
PAINT GREEN (-673 50);
DISPLAY INVISIBLE (-673 50);
FORCEADD TAP..1
(2750 350);
FORCEPROP 3 LASTPIN (2700 350) SIG_NAME M_C_CPU1_SB_CS_N<3>
J 0
(2710 360);
DISPLAY 0.659574 (2710 360);
PAINT MONO (2710 360);
DISPLAY INVISIBLE (2710 360);
FORCEPROP 1 LASTPIN (2700 350) BN 3
J 0
(2688 358);
DISPLAY 0.680851 (2688 358);
PAINT GREEN (2688 358);
FORCEPROP 2 LAST CDS_LIB standard
J 0
(2750 350);
DISPLAY INVISIBLE (2750 350);
FORCEPROP 1 LAST BODY_TYPE PLUMBING
J 0
(2750 400);
DISPLAY 0.872340 (2750 400);
PAINT GREEN (2750 400);
DISPLAY INVISIBLE (2750 400);
FORCEPROP 1 LAST HDL_TAP TRUE
J 0
(3075 225);
DISPLAY 0.872340 (3075 225);
DISPLAY INVISIBLE (3075 225);
FORCEPROP 1 LAST PATH I100
J 0
(2748 350);
DISPLAY 0.872340 (2748 350);
PAINT GREEN (2748 350);
DISPLAY INVISIBLE (2748 350);
FORCEADD TAP..1
(2750 550);
FORCEPROP 3 LASTPIN (2700 550) SIG_NAME M_C_CPU1_SA_CS_N<1>
J 0
(2710 560);
DISPLAY 0.659574 (2710 560);
PAINT MONO (2710 560);
DISPLAY INVISIBLE (2710 560);
FORCEPROP 1 LASTPIN (2700 550) BN 1
J 0
(2688 558);
DISPLAY 0.680851 (2688 558);
PAINT GREEN (2688 558);
FORCEPROP 2 LAST CDS_LIB standard
J 0
(2750 550);
DISPLAY INVISIBLE (2750 550);
FORCEPROP 1 LAST BODY_TYPE PLUMBING
J 0
(2750 600);
DISPLAY 0.872340 (2750 600);
PAINT GREEN (2750 600);
DISPLAY INVISIBLE (2750 600);
FORCEPROP 1 LAST HDL_TAP TRUE
J 0
(3075 425);
DISPLAY 0.872340 (3075 425);
DISPLAY INVISIBLE (3075 425);
FORCEPROP 1 LAST PATH I101
J 0
(2748 550);
DISPLAY 0.872340 (2748 550);
PAINT GREEN (2748 550);
DISPLAY INVISIBLE (2748 550);
FORCEADD TAP..1
(2750 500);
FORCEPROP 3 LASTPIN (2700 500) SIG_NAME M_C_CPU1_SA_CS_N<0>
J 0
(2710 510);
DISPLAY 0.659574 (2710 510);
PAINT MONO (2710 510);
DISPLAY INVISIBLE (2710 510);
FORCEPROP 1 LASTPIN (2700 500) BN 0
J 0
(2688 508);
DISPLAY 0.680851 (2688 508);
PAINT GREEN (2688 508);
FORCEPROP 2 LAST CDS_LIB standard
J 0
(2750 500);
DISPLAY INVISIBLE (2750 500);
FORCEPROP 1 LAST BODY_TYPE PLUMBING
J 0
(2750 550);
DISPLAY 0.872340 (2750 550);
PAINT GREEN (2750 550);
DISPLAY INVISIBLE (2750 550);
FORCEPROP 1 LAST HDL_TAP TRUE
J 0
(3075 375);
DISPLAY 0.872340 (3075 375);
DISPLAY INVISIBLE (3075 375);
FORCEPROP 1 LAST PATH I102
J 0
(2748 500);
DISPLAY 0.872340 (2748 500);
PAINT GREEN (2748 500);
DISPLAY INVISIBLE (2748 500);
FORCEADD TAP..1
(2750 600);
FORCEPROP 3 LASTPIN (2700 600) SIG_NAME M_C_CPU1_SA_CS_N<2>
J 0
(2710 610);
DISPLAY 0.659574 (2710 610);
PAINT MONO (2710 610);
DISPLAY INVISIBLE (2710 610);
FORCEPROP 1 LASTPIN (2700 600) BN 2
J 0
(2688 608);
DISPLAY 0.680851 (2688 608);
PAINT GREEN (2688 608);
FORCEPROP 2 LAST CDS_LIB standard
J 0
(2750 600);
DISPLAY INVISIBLE (2750 600);
FORCEPROP 1 LAST BODY_TYPE PLUMBING
J 0
(2750 650);
DISPLAY 0.872340 (2750 650);
PAINT GREEN (2750 650);
DISPLAY INVISIBLE (2750 650);
FORCEPROP 1 LAST HDL_TAP TRUE
J 0
(3075 475);
DISPLAY 0.872340 (3075 475);
DISPLAY INVISIBLE (3075 475);
FORCEPROP 1 LAST PATH I103
J 0
(2748 600);
DISPLAY 0.872340 (2748 600);
PAINT GREEN (2748 600);
DISPLAY INVISIBLE (2748 600);
FORCEADD TAP..1
(2750 650);
FORCEPROP 3 LASTPIN (2700 650) SIG_NAME M_C_CPU1_SA_CS_N<3>
J 0
(2710 660);
DISPLAY 0.659574 (2710 660);
PAINT MONO (2710 660);
DISPLAY INVISIBLE (2710 660);
FORCEPROP 1 LASTPIN (2700 650) BN 3
J 0
(2688 658);
DISPLAY 0.680851 (2688 658);
PAINT GREEN (2688 658);
FORCEPROP 2 LAST CDS_LIB standard
J 0
(2750 650);
DISPLAY INVISIBLE (2750 650);
FORCEPROP 1 LAST BODY_TYPE PLUMBING
J 0
(2750 700);
DISPLAY 0.872340 (2750 700);
PAINT GREEN (2750 700);
DISPLAY INVISIBLE (2750 700);
FORCEPROP 1 LAST HDL_TAP TRUE
J 0
(3075 525);
DISPLAY 0.872340 (3075 525);
DISPLAY INVISIBLE (3075 525);
FORCEPROP 1 LAST PATH I104
J 0
(2748 650);
DISPLAY 0.872340 (2748 650);
PAINT GREEN (2748 650);
DISPLAY INVISIBLE (2748 650);
FORCEADD TAP..1
(2750 950);
FORCEPROP 3 LASTPIN (2700 950) SIG_NAME M_C_CPU1_SB_CA<2>
J 0
(2710 960);
DISPLAY 0.659574 (2710 960);
PAINT MONO (2710 960);
DISPLAY INVISIBLE (2710 960);
FORCEPROP 1 LASTPIN (2700 950) BN 2
J 0
(2688 958);
DISPLAY 0.680851 (2688 958);
PAINT GREEN (2688 958);
FORCEPROP 2 LAST CDS_LIB standard
J 0
(2750 950);
DISPLAY INVISIBLE (2750 950);
FORCEPROP 1 LAST BODY_TYPE PLUMBING
J 0
(2750 1000);
DISPLAY 0.872340 (2750 1000);
PAINT GREEN (2750 1000);
DISPLAY INVISIBLE (2750 1000);
FORCEPROP 1 LAST HDL_TAP TRUE
J 0
(3075 825);
DISPLAY 0.872340 (3075 825);
DISPLAY INVISIBLE (3075 825);
FORCEPROP 1 LAST PATH I105
J 0
(2748 950);
DISPLAY 0.872340 (2748 950);
PAINT GREEN (2748 950);
DISPLAY INVISIBLE (2748 950);
FORCEADD TAP..1
(2750 850);
FORCEPROP 3 LASTPIN (2700 850) SIG_NAME M_C_CPU1_SB_CA<0>
J 0
(2710 860);
DISPLAY 0.659574 (2710 860);
PAINT MONO (2710 860);
DISPLAY INVISIBLE (2710 860);
FORCEPROP 1 LASTPIN (2700 850) BN 0
J 0
(2688 858);
DISPLAY 0.680851 (2688 858);
PAINT GREEN (2688 858);
FORCEPROP 2 LAST CDS_LIB standard
J 0
(2750 850);
DISPLAY INVISIBLE (2750 850);
FORCEPROP 1 LAST BODY_TYPE PLUMBING
J 0
(2750 900);
DISPLAY 0.872340 (2750 900);
PAINT GREEN (2750 900);
DISPLAY INVISIBLE (2750 900);
FORCEPROP 1 LAST HDL_TAP TRUE
J 0
(3075 725);
DISPLAY 0.872340 (3075 725);
DISPLAY INVISIBLE (3075 725);
FORCEPROP 1 LAST PATH I106
J 0
(2748 850);
DISPLAY 0.872340 (2748 850);
PAINT GREEN (2748 850);
DISPLAY INVISIBLE (2748 850);
FORCEADD TAP..1
(2750 900);
FORCEPROP 3 LASTPIN (2700 900) SIG_NAME M_C_CPU1_SB_CA<1>
J 0
(2710 910);
DISPLAY 0.659574 (2710 910);
PAINT MONO (2710 910);
DISPLAY INVISIBLE (2710 910);
FORCEPROP 1 LASTPIN (2700 900) BN 1
J 0
(2688 908);
DISPLAY 0.680851 (2688 908);
PAINT GREEN (2688 908);
FORCEPROP 2 LAST CDS_LIB standard
J 0
(2750 900);
DISPLAY INVISIBLE (2750 900);
FORCEPROP 1 LAST BODY_TYPE PLUMBING
J 0
(2750 950);
DISPLAY 0.872340 (2750 950);
PAINT GREEN (2750 950);
DISPLAY INVISIBLE (2750 950);
FORCEPROP 1 LAST HDL_TAP TRUE
J 0
(3075 775);
DISPLAY 0.872340 (3075 775);
DISPLAY INVISIBLE (3075 775);
FORCEPROP 1 LAST PATH I107
J 0
(2748 900);
DISPLAY 0.872340 (2748 900);
PAINT GREEN (2748 900);
DISPLAY INVISIBLE (2748 900);
FORCEADD TAP..1
(2750 1050);
FORCEPROP 3 LASTPIN (2700 1050) SIG_NAME M_C_CPU1_SB_CA<4>
J 0
(2710 1060);
DISPLAY 0.659574 (2710 1060);
PAINT MONO (2710 1060);
DISPLAY INVISIBLE (2710 1060);
FORCEPROP 1 LASTPIN (2700 1050) BN 4
J 0
(2688 1058);
DISPLAY 0.680851 (2688 1058);
PAINT GREEN (2688 1058);
FORCEPROP 2 LAST CDS_LIB standard
J 0
(2750 1050);
DISPLAY INVISIBLE (2750 1050);
FORCEPROP 1 LAST BODY_TYPE PLUMBING
J 0
(2750 1100);
DISPLAY 0.872340 (2750 1100);
PAINT GREEN (2750 1100);
DISPLAY INVISIBLE (2750 1100);
FORCEPROP 1 LAST HDL_TAP TRUE
J 0
(3075 925);
DISPLAY 0.872340 (3075 925);
DISPLAY INVISIBLE (3075 925);
FORCEPROP 1 LAST PATH I108
J 0
(2748 1050);
DISPLAY 0.872340 (2748 1050);
PAINT GREEN (2748 1050);
DISPLAY INVISIBLE (2748 1050);
FORCEADD TAP..1
(2750 1000);
FORCEPROP 3 LASTPIN (2700 1000) SIG_NAME M_C_CPU1_SB_CA<3>
J 0
(2710 1010);
DISPLAY 0.659574 (2710 1010);
PAINT MONO (2710 1010);
DISPLAY INVISIBLE (2710 1010);
FORCEPROP 1 LASTPIN (2700 1000) BN 3
J 0
(2688 1008);
DISPLAY 0.680851 (2688 1008);
PAINT GREEN (2688 1008);
FORCEPROP 2 LAST CDS_LIB standard
J 0
(2750 1000);
DISPLAY INVISIBLE (2750 1000);
FORCEPROP 1 LAST BODY_TYPE PLUMBING
J 0
(2750 1050);
DISPLAY 0.872340 (2750 1050);
PAINT GREEN (2750 1050);
DISPLAY INVISIBLE (2750 1050);
FORCEPROP 1 LAST HDL_TAP TRUE
J 0
(3075 875);
DISPLAY 0.872340 (3075 875);
DISPLAY INVISIBLE (3075 875);
FORCEPROP 1 LAST PATH I109
J 0
(2748 1000);
DISPLAY 0.872340 (2748 1000);
PAINT GREEN (2748 1000);
DISPLAY INVISIBLE (2748 1000);
FORCEADD TAP..1
R 2
(-675 200);
FORCEPROP 3 LASTPIN (-625 200) SIG_NAME M_C_CPU1_SB_CB<4>
J 0
(-615 210);
DISPLAY 0.659574 (-615 210);
PAINT MONO (-615 210);
DISPLAY INVISIBLE (-615 210);
FORCEPROP 1 LASTPIN (-625 200) BN 4
J 2
(-613 208);
DISPLAY 0.680851 (-613 208);
PAINT GREEN (-613 208);
FORCEPROP 2 LAST CDS_LIB standard
J 0
(-675 200);
DISPLAY INVISIBLE (-675 200);
FORCEPROP 1 LAST BODY_TYPE PLUMBING
J 2
(-675 250);
DISPLAY 0.872340 (-675 250);
PAINT GREEN (-675 250);
DISPLAY INVISIBLE (-675 250);
FORCEPROP 1 LAST HDL_TAP TRUE
J 2
(-1000 75);
DISPLAY 0.872340 (-1000 75);
DISPLAY INVISIBLE (-1000 75);
FORCEPROP 1 LAST PATH I11
J 2
(-673 200);
DISPLAY 0.872340 (-673 200);
PAINT GREEN (-673 200);
DISPLAY INVISIBLE (-673 200);
FORCEADD TAP..1
(2750 1150);
FORCEPROP 3 LASTPIN (2700 1150) SIG_NAME M_C_CPU1_SB_CA<6>
J 0
(2710 1160);
DISPLAY 0.659574 (2710 1160);
PAINT MONO (2710 1160);
DISPLAY INVISIBLE (2710 1160);
FORCEPROP 1 LASTPIN (2700 1150) BN 6
J 0
(2688 1158);
DISPLAY 0.680851 (2688 1158);
PAINT GREEN (2688 1158);
FORCEPROP 2 LAST CDS_LIB standard
J 0
(2750 1150);
DISPLAY INVISIBLE (2750 1150);
FORCEPROP 1 LAST BODY_TYPE PLUMBING
J 0
(2750 1200);
DISPLAY 0.872340 (2750 1200);
PAINT GREEN (2750 1200);
DISPLAY INVISIBLE (2750 1200);
FORCEPROP 1 LAST HDL_TAP TRUE
J 0
(3075 1025);
DISPLAY 0.872340 (3075 1025);
DISPLAY INVISIBLE (3075 1025);
FORCEPROP 1 LAST PATH I110
J 0
(2748 1150);
DISPLAY 0.872340 (2748 1150);
PAINT GREEN (2748 1150);
DISPLAY INVISIBLE (2748 1150);
FORCEADD TAP..1
(2750 1100);
FORCEPROP 3 LASTPIN (2700 1100) SIG_NAME M_C_CPU1_SB_CA<5>
J 0
(2710 1110);
DISPLAY 0.659574 (2710 1110);
PAINT MONO (2710 1110);
DISPLAY INVISIBLE (2710 1110);
FORCEPROP 1 LASTPIN (2700 1100) BN 5
J 0
(2688 1108);
DISPLAY 0.680851 (2688 1108);
PAINT GREEN (2688 1108);
FORCEPROP 2 LAST CDS_LIB standard
J 0
(2750 1100);
DISPLAY INVISIBLE (2750 1100);
FORCEPROP 1 LAST BODY_TYPE PLUMBING
J 0
(2750 1150);
DISPLAY 0.872340 (2750 1150);
PAINT GREEN (2750 1150);
DISPLAY INVISIBLE (2750 1150);
FORCEPROP 1 LAST HDL_TAP TRUE
J 0
(3075 975);
DISPLAY 0.872340 (3075 975);
DISPLAY INVISIBLE (3075 975);
FORCEPROP 1 LAST PATH I111
J 0
(2748 1100);
DISPLAY 0.872340 (2748 1100);
PAINT GREEN (2748 1100);
DISPLAY INVISIBLE (2748 1100);
FORCEADD TAP..1
(2750 1400);
FORCEPROP 3 LASTPIN (2700 1400) SIG_NAME M_C_CPU1_SA_CA<1>
J 0
(2710 1410);
DISPLAY 0.659574 (2710 1410);
PAINT MONO (2710 1410);
DISPLAY INVISIBLE (2710 1410);
FORCEPROP 1 LASTPIN (2700 1400) BN 1
J 0
(2688 1408);
DISPLAY 0.680851 (2688 1408);
PAINT GREEN (2688 1408);
FORCEPROP 2 LAST CDS_LIB standard
J 0
(2750 1400);
DISPLAY INVISIBLE (2750 1400);
FORCEPROP 1 LAST BODY_TYPE PLUMBING
J 0
(2750 1450);
DISPLAY 0.872340 (2750 1450);
PAINT GREEN (2750 1450);
DISPLAY INVISIBLE (2750 1450);
FORCEPROP 1 LAST HDL_TAP TRUE
J 0
(3075 1275);
DISPLAY 0.872340 (3075 1275);
DISPLAY INVISIBLE (3075 1275);
FORCEPROP 1 LAST PATH I112
J 0
(2748 1400);
DISPLAY 0.872340 (2748 1400);
PAINT GREEN (2748 1400);
DISPLAY INVISIBLE (2748 1400);
FORCEADD TAP..1
(2750 1350);
FORCEPROP 3 LASTPIN (2700 1350) SIG_NAME M_C_CPU1_SA_CA<0>
J 0
(2710 1360);
DISPLAY 0.659574 (2710 1360);
PAINT MONO (2710 1360);
DISPLAY INVISIBLE (2710 1360);
FORCEPROP 1 LASTPIN (2700 1350) BN 0
J 0
(2688 1358);
DISPLAY 0.680851 (2688 1358);
PAINT GREEN (2688 1358);
FORCEPROP 2 LAST CDS_LIB standard
J 0
(2750 1350);
DISPLAY INVISIBLE (2750 1350);
FORCEPROP 1 LAST BODY_TYPE PLUMBING
J 0
(2750 1400);
DISPLAY 0.872340 (2750 1400);
PAINT GREEN (2750 1400);
DISPLAY INVISIBLE (2750 1400);
FORCEPROP 1 LAST HDL_TAP TRUE
J 0
(3075 1225);
DISPLAY 0.872340 (3075 1225);
DISPLAY INVISIBLE (3075 1225);
FORCEPROP 1 LAST PATH I113
J 0
(2748 1350);
DISPLAY 0.872340 (2748 1350);
PAINT GREEN (2748 1350);
DISPLAY INVISIBLE (2748 1350);
FORCEADD TAP..1
(2750 1450);
FORCEPROP 3 LASTPIN (2700 1450) SIG_NAME M_C_CPU1_SA_CA<2>
J 0
(2710 1460);
DISPLAY 0.659574 (2710 1460);
PAINT MONO (2710 1460);
DISPLAY INVISIBLE (2710 1460);
FORCEPROP 1 LASTPIN (2700 1450) BN 2
J 0
(2688 1458);
DISPLAY 0.680851 (2688 1458);
PAINT GREEN (2688 1458);
FORCEPROP 2 LAST CDS_LIB standard
J 0
(2750 1450);
DISPLAY INVISIBLE (2750 1450);
FORCEPROP 1 LAST BODY_TYPE PLUMBING
J 0
(2750 1500);
DISPLAY 0.872340 (2750 1500);
PAINT GREEN (2750 1500);
DISPLAY INVISIBLE (2750 1500);
FORCEPROP 1 LAST HDL_TAP TRUE
J 0
(3075 1325);
DISPLAY 0.872340 (3075 1325);
DISPLAY INVISIBLE (3075 1325);
FORCEPROP 1 LAST PATH I114
J 0
(2748 1450);
DISPLAY 0.872340 (2748 1450);
PAINT GREEN (2748 1450);
DISPLAY INVISIBLE (2748 1450);
FORCEADD TAP..1
(2750 1550);
FORCEPROP 3 LASTPIN (2700 1550) SIG_NAME M_C_CPU1_SA_CA<4>
J 0
(2710 1560);
DISPLAY 0.659574 (2710 1560);
PAINT MONO (2710 1560);
DISPLAY INVISIBLE (2710 1560);
FORCEPROP 1 LASTPIN (2700 1550) BN 4
J 0
(2688 1558);
DISPLAY 0.680851 (2688 1558);
PAINT GREEN (2688 1558);
FORCEPROP 2 LAST CDS_LIB standard
J 0
(2750 1550);
DISPLAY INVISIBLE (2750 1550);
FORCEPROP 1 LAST BODY_TYPE PLUMBING
J 0
(2750 1600);
DISPLAY 0.872340 (2750 1600);
PAINT GREEN (2750 1600);
DISPLAY INVISIBLE (2750 1600);
FORCEPROP 1 LAST HDL_TAP TRUE
J 0
(3075 1425);
DISPLAY 0.872340 (3075 1425);
DISPLAY INVISIBLE (3075 1425);
FORCEPROP 1 LAST PATH I115
J 0
(2748 1550);
DISPLAY 0.872340 (2748 1550);
PAINT GREEN (2748 1550);
DISPLAY INVISIBLE (2748 1550);
FORCEADD TAP..1
(2750 1600);
FORCEPROP 3 LASTPIN (2700 1600) SIG_NAME M_C_CPU1_SA_CA<5>
J 0
(2710 1610);
DISPLAY 0.659574 (2710 1610);
PAINT MONO (2710 1610);
DISPLAY INVISIBLE (2710 1610);
FORCEPROP 1 LASTPIN (2700 1600) BN 5
J 0
(2688 1608);
DISPLAY 0.680851 (2688 1608);
PAINT GREEN (2688 1608);
FORCEPROP 2 LAST CDS_LIB standard
J 0
(2750 1600);
DISPLAY INVISIBLE (2750 1600);
FORCEPROP 1 LAST BODY_TYPE PLUMBING
J 0
(2750 1650);
DISPLAY 0.872340 (2750 1650);
PAINT GREEN (2750 1650);
DISPLAY INVISIBLE (2750 1650);
FORCEPROP 1 LAST HDL_TAP TRUE
J 0
(3075 1475);
DISPLAY 0.872340 (3075 1475);
DISPLAY INVISIBLE (3075 1475);
FORCEPROP 1 LAST PATH I116
J 0
(2748 1600);
DISPLAY 0.872340 (2748 1600);
PAINT GREEN (2748 1600);
DISPLAY INVISIBLE (2748 1600);
FORCEADD TAP..1
(2750 1500);
FORCEPROP 3 LASTPIN (2700 1500) SIG_NAME M_C_CPU1_SA_CA<3>
J 0
(2710 1510);
DISPLAY 0.659574 (2710 1510);
PAINT MONO (2710 1510);
DISPLAY INVISIBLE (2710 1510);
FORCEPROP 1 LASTPIN (2700 1500) BN 3
J 0
(2688 1508);
DISPLAY 0.680851 (2688 1508);
PAINT GREEN (2688 1508);
FORCEPROP 2 LAST CDS_LIB standard
J 0
(2750 1500);
DISPLAY INVISIBLE (2750 1500);
FORCEPROP 1 LAST BODY_TYPE PLUMBING
J 0
(2750 1550);
DISPLAY 0.872340 (2750 1550);
PAINT GREEN (2750 1550);
DISPLAY INVISIBLE (2750 1550);
FORCEPROP 1 LAST HDL_TAP TRUE
J 0
(3075 1375);
DISPLAY 0.872340 (3075 1375);
DISPLAY INVISIBLE (3075 1375);
FORCEPROP 1 LAST PATH I117
J 0
(2748 1500);
DISPLAY 0.872340 (2748 1500);
PAINT GREEN (2748 1500);
DISPLAY INVISIBLE (2748 1500);
FORCEADD TAP..1
(2750 1650);
FORCEPROP 3 LASTPIN (2700 1650) SIG_NAME M_C_CPU1_SA_CA<6>
J 0
(2710 1660);
DISPLAY 0.659574 (2710 1660);
PAINT MONO (2710 1660);
DISPLAY INVISIBLE (2710 1660);
FORCEPROP 1 LASTPIN (2700 1650) BN 6
J 0
(2688 1658);
DISPLAY 0.680851 (2688 1658);
PAINT GREEN (2688 1658);
FORCEPROP 2 LAST CDS_LIB standard
J 0
(2750 1650);
DISPLAY INVISIBLE (2750 1650);
FORCEPROP 1 LAST BODY_TYPE PLUMBING
J 0
(2750 1700);
DISPLAY 0.872340 (2750 1700);
PAINT GREEN (2750 1700);
DISPLAY INVISIBLE (2750 1700);
FORCEPROP 1 LAST HDL_TAP TRUE
J 0
(3075 1525);
DISPLAY 0.872340 (3075 1525);
DISPLAY INVISIBLE (3075 1525);
FORCEPROP 1 LAST PATH I118
J 0
(2748 1650);
DISPLAY 0.872340 (2748 1650);
PAINT GREEN (2748 1650);
DISPLAY INVISIBLE (2748 1650);
FORCEADD TAP..1
(2750 1800);
FORCEPROP 3 LASTPIN (2700 1800) SIG_NAME M_C_CPU1_SB_DQS_DN<0>
J 0
(2710 1810);
DISPLAY 0.659574 (2710 1810);
PAINT MONO (2710 1810);
DISPLAY INVISIBLE (2710 1810);
FORCEPROP 1 LASTPIN (2700 1800) BN 0
J 0
(2688 1808);
DISPLAY 0.680851 (2688 1808);
PAINT GREEN (2688 1808);
FORCEPROP 2 LAST CDS_LIB standard
J 0
(2750 1800);
DISPLAY INVISIBLE (2750 1800);
FORCEPROP 1 LAST BODY_TYPE PLUMBING
J 0
(2750 1850);
DISPLAY 0.872340 (2750 1850);
PAINT GREEN (2750 1850);
DISPLAY INVISIBLE (2750 1850);
FORCEPROP 1 LAST HDL_TAP TRUE
J 0
(3075 1675);
DISPLAY 0.872340 (3075 1675);
DISPLAY INVISIBLE (3075 1675);
FORCEPROP 1 LAST PATH I119
J 0
(2748 1800);
DISPLAY 0.872340 (2748 1800);
PAINT GREEN (2748 1800);
DISPLAY INVISIBLE (2748 1800);
FORCEADD TAP..1
R 2
(-675 250);
FORCEPROP 3 LASTPIN (-625 250) SIG_NAME M_C_CPU1_SB_CB<5>
J 0
(-615 260);
DISPLAY 0.659574 (-615 260);
PAINT MONO (-615 260);
DISPLAY INVISIBLE (-615 260);
FORCEPROP 1 LASTPIN (-625 250) BN 5
J 2
(-613 258);
DISPLAY 0.680851 (-613 258);
PAINT GREEN (-613 258);
FORCEPROP 2 LAST CDS_LIB standard
J 0
(-675 250);
DISPLAY INVISIBLE (-675 250);
FORCEPROP 1 LAST BODY_TYPE PLUMBING
J 2
(-675 300);
DISPLAY 0.872340 (-675 300);
PAINT GREEN (-675 300);
DISPLAY INVISIBLE (-675 300);
FORCEPROP 1 LAST HDL_TAP TRUE
J 2
(-1000 125);
DISPLAY 0.872340 (-1000 125);
DISPLAY INVISIBLE (-1000 125);
FORCEPROP 1 LAST PATH I12
J 2
(-673 250);
DISPLAY 0.872340 (-673 250);
PAINT GREEN (-673 250);
DISPLAY INVISIBLE (-673 250);
FORCEADD TAP..1
(2750 1850);
FORCEPROP 3 LASTPIN (2700 1850) SIG_NAME M_C_CPU1_SB_DQS_DN<1>
J 0
(2710 1860);
DISPLAY 0.659574 (2710 1860);
PAINT MONO (2710 1860);
DISPLAY INVISIBLE (2710 1860);
FORCEPROP 1 LASTPIN (2700 1850) BN 1
J 0
(2688 1858);
DISPLAY 0.680851 (2688 1858);
PAINT GREEN (2688 1858);
FORCEPROP 2 LAST CDS_LIB standard
J 0
(2750 1850);
DISPLAY INVISIBLE (2750 1850);
FORCEPROP 1 LAST BODY_TYPE PLUMBING
J 0
(2750 1900);
DISPLAY 0.872340 (2750 1900);
PAINT GREEN (2750 1900);
DISPLAY INVISIBLE (2750 1900);
FORCEPROP 1 LAST HDL_TAP TRUE
J 0
(3075 1725);
DISPLAY 0.872340 (3075 1725);
DISPLAY INVISIBLE (3075 1725);
FORCEPROP 1 LAST PATH I120
J 0
(2748 1850);
DISPLAY 0.872340 (2748 1850);
PAINT GREEN (2748 1850);
DISPLAY INVISIBLE (2748 1850);
FORCEADD TAP..1
(2750 1900);
FORCEPROP 3 LASTPIN (2700 1900) SIG_NAME M_C_CPU1_SB_DQS_DN<2>
J 0
(2710 1910);
DISPLAY 0.659574 (2710 1910);
PAINT MONO (2710 1910);
DISPLAY INVISIBLE (2710 1910);
FORCEPROP 1 LASTPIN (2700 1900) BN 2
J 0
(2688 1908);
DISPLAY 0.680851 (2688 1908);
PAINT GREEN (2688 1908);
FORCEPROP 2 LAST CDS_LIB standard
J 0
(2750 1900);
DISPLAY INVISIBLE (2750 1900);
FORCEPROP 1 LAST BODY_TYPE PLUMBING
J 0
(2750 1950);
DISPLAY 0.872340 (2750 1950);
PAINT GREEN (2750 1950);
DISPLAY INVISIBLE (2750 1950);
FORCEPROP 1 LAST HDL_TAP TRUE
J 0
(3075 1775);
DISPLAY 0.872340 (3075 1775);
DISPLAY INVISIBLE (3075 1775);
FORCEPROP 1 LAST PATH I121
J 0
(2748 1900);
DISPLAY 0.872340 (2748 1900);
PAINT GREEN (2748 1900);
DISPLAY INVISIBLE (2748 1900);
FORCEADD TAP..1
(2750 1950);
FORCEPROP 3 LASTPIN (2700 1950) SIG_NAME M_C_CPU1_SB_DQS_DN<3>
J 0
(2710 1960);
DISPLAY 0.659574 (2710 1960);
PAINT MONO (2710 1960);
DISPLAY INVISIBLE (2710 1960);
FORCEPROP 1 LASTPIN (2700 1950) BN 3
J 0
(2688 1958);
DISPLAY 0.680851 (2688 1958);
PAINT GREEN (2688 1958);
FORCEPROP 2 LAST CDS_LIB standard
J 0
(2750 1950);
DISPLAY INVISIBLE (2750 1950);
FORCEPROP 1 LAST BODY_TYPE PLUMBING
J 0
(2750 2000);
DISPLAY 0.872340 (2750 2000);
PAINT GREEN (2750 2000);
DISPLAY INVISIBLE (2750 2000);
FORCEPROP 1 LAST HDL_TAP TRUE
J 0
(3075 1825);
DISPLAY 0.872340 (3075 1825);
DISPLAY INVISIBLE (3075 1825);
FORCEPROP 1 LAST PATH I122
J 0
(2748 1950);
DISPLAY 0.872340 (2748 1950);
PAINT GREEN (2748 1950);
DISPLAY INVISIBLE (2748 1950);
FORCEADD TAP..1
(2750 2100);
FORCEPROP 3 LASTPIN (2700 2100) SIG_NAME M_C_CPU1_SB_DQS_DN<6>
J 0
(2710 2110);
DISPLAY 0.659574 (2710 2110);
PAINT MONO (2710 2110);
DISPLAY INVISIBLE (2710 2110);
FORCEPROP 1 LASTPIN (2700 2100) BN 6
J 0
(2688 2108);
DISPLAY 0.680851 (2688 2108);
PAINT GREEN (2688 2108);
FORCEPROP 2 LAST CDS_LIB standard
J 0
(2750 2100);
DISPLAY INVISIBLE (2750 2100);
FORCEPROP 1 LAST BODY_TYPE PLUMBING
J 0
(2750 2150);
DISPLAY 0.872340 (2750 2150);
PAINT GREEN (2750 2150);
DISPLAY INVISIBLE (2750 2150);
FORCEPROP 1 LAST HDL_TAP TRUE
J 0
(3075 1975);
DISPLAY 0.872340 (3075 1975);
DISPLAY INVISIBLE (3075 1975);
FORCEPROP 1 LAST PATH I123
J 0
(2748 2100);
DISPLAY 0.872340 (2748 2100);
PAINT GREEN (2748 2100);
DISPLAY INVISIBLE (2748 2100);
FORCEADD TAP..1
(2750 2050);
FORCEPROP 3 LASTPIN (2700 2050) SIG_NAME M_C_CPU1_SB_DQS_DN<5>
J 0
(2710 2060);
DISPLAY 0.659574 (2710 2060);
PAINT MONO (2710 2060);
DISPLAY INVISIBLE (2710 2060);
FORCEPROP 1 LASTPIN (2700 2050) BN 5
J 0
(2688 2058);
DISPLAY 0.680851 (2688 2058);
PAINT GREEN (2688 2058);
FORCEPROP 2 LAST CDS_LIB standard
J 0
(2750 2050);
DISPLAY INVISIBLE (2750 2050);
FORCEPROP 1 LAST BODY_TYPE PLUMBING
J 0
(2750 2100);
DISPLAY 0.872340 (2750 2100);
PAINT GREEN (2750 2100);
DISPLAY INVISIBLE (2750 2100);
FORCEPROP 1 LAST HDL_TAP TRUE
J 0
(3075 1925);
DISPLAY 0.872340 (3075 1925);
DISPLAY INVISIBLE (3075 1925);
FORCEPROP 1 LAST PATH I124
J 0
(2748 2050);
DISPLAY 0.872340 (2748 2050);
PAINT GREEN (2748 2050);
DISPLAY INVISIBLE (2748 2050);
FORCEADD TAP..1
(2750 2000);
FORCEPROP 3 LASTPIN (2700 2000) SIG_NAME M_C_CPU1_SB_DQS_DN<4>
J 0
(2710 2010);
DISPLAY 0.659574 (2710 2010);
PAINT MONO (2710 2010);
DISPLAY INVISIBLE (2710 2010);
FORCEPROP 1 LASTPIN (2700 2000) BN 4
J 0
(2688 2008);
DISPLAY 0.680851 (2688 2008);
PAINT GREEN (2688 2008);
FORCEPROP 2 LAST CDS_LIB standard
J 0
(2750 2000);
DISPLAY INVISIBLE (2750 2000);
FORCEPROP 1 LAST BODY_TYPE PLUMBING
J 0
(2750 2050);
DISPLAY 0.872340 (2750 2050);
PAINT GREEN (2750 2050);
DISPLAY INVISIBLE (2750 2050);
FORCEPROP 1 LAST HDL_TAP TRUE
J 0
(3075 1875);
DISPLAY 0.872340 (3075 1875);
DISPLAY INVISIBLE (3075 1875);
FORCEPROP 1 LAST PATH I125
J 0
(2748 2000);
DISPLAY 0.872340 (2748 2000);
PAINT GREEN (2748 2000);
DISPLAY INVISIBLE (2748 2000);
FORCEADD TAP..1
(2750 2200);
FORCEPROP 3 LASTPIN (2700 2200) SIG_NAME M_C_CPU1_SB_DQS_DN<8>
J 0
(2710 2210);
DISPLAY 0.659574 (2710 2210);
PAINT MONO (2710 2210);
DISPLAY INVISIBLE (2710 2210);
FORCEPROP 1 LASTPIN (2700 2200) BN 8
J 0
(2688 2208);
DISPLAY 0.680851 (2688 2208);
PAINT GREEN (2688 2208);
FORCEPROP 2 LAST CDS_LIB standard
J 0
(2750 2200);
DISPLAY INVISIBLE (2750 2200);
FORCEPROP 1 LAST BODY_TYPE PLUMBING
J 0
(2750 2250);
DISPLAY 0.872340 (2750 2250);
PAINT GREEN (2750 2250);
DISPLAY INVISIBLE (2750 2250);
FORCEPROP 1 LAST HDL_TAP TRUE
J 0
(3075 2075);
DISPLAY 0.872340 (3075 2075);
DISPLAY INVISIBLE (3075 2075);
FORCEPROP 1 LAST PATH I126
J 0
(2748 2200);
DISPLAY 0.872340 (2748 2200);
PAINT GREEN (2748 2200);
DISPLAY INVISIBLE (2748 2200);
FORCEADD TAP..1
(2750 2150);
FORCEPROP 3 LASTPIN (2700 2150) SIG_NAME M_C_CPU1_SB_DQS_DN<7>
J 0
(2710 2160);
DISPLAY 0.659574 (2710 2160);
PAINT MONO (2710 2160);
DISPLAY INVISIBLE (2710 2160);
FORCEPROP 1 LASTPIN (2700 2150) BN 7
J 0
(2688 2158);
DISPLAY 0.680851 (2688 2158);
PAINT GREEN (2688 2158);
FORCEPROP 2 LAST CDS_LIB standard
J 0
(2750 2150);
DISPLAY INVISIBLE (2750 2150);
FORCEPROP 1 LAST BODY_TYPE PLUMBING
J 0
(2750 2200);
DISPLAY 0.872340 (2750 2200);
PAINT GREEN (2750 2200);
DISPLAY INVISIBLE (2750 2200);
FORCEPROP 1 LAST HDL_TAP TRUE
J 0
(3075 2025);
DISPLAY 0.872340 (3075 2025);
DISPLAY INVISIBLE (3075 2025);
FORCEPROP 1 LAST PATH I127
J 0
(2748 2150);
DISPLAY 0.872340 (2748 2150);
PAINT GREEN (2748 2150);
DISPLAY INVISIBLE (2748 2150);
FORCEADD TAP..1
(2750 2250);
FORCEPROP 3 LASTPIN (2700 2250) SIG_NAME M_C_CPU1_SB_DQS_DN<9>
J 0
(2710 2260);
DISPLAY 0.659574 (2710 2260);
PAINT MONO (2710 2260);
DISPLAY INVISIBLE (2710 2260);
FORCEPROP 1 LASTPIN (2700 2250) BN 9
J 0
(2688 2258);
DISPLAY 0.680851 (2688 2258);
PAINT GREEN (2688 2258);
FORCEPROP 2 LAST CDS_LIB standard
J 0
(2750 2250);
DISPLAY INVISIBLE (2750 2250);
FORCEPROP 1 LAST BODY_TYPE PLUMBING
J 0
(2750 2300);
DISPLAY 0.872340 (2750 2300);
PAINT GREEN (2750 2300);
DISPLAY INVISIBLE (2750 2300);
FORCEPROP 1 LAST HDL_TAP TRUE
J 0
(3075 2125);
DISPLAY 0.872340 (3075 2125);
DISPLAY INVISIBLE (3075 2125);
FORCEPROP 1 LAST PATH I128
J 0
(2748 2250);
DISPLAY 0.872340 (2748 2250);
PAINT GREEN (2748 2250);
DISPLAY INVISIBLE (2748 2250);
FORCEADD TAP..1
(2750 2350);
FORCEPROP 3 LASTPIN (2700 2350) SIG_NAME M_C_CPU1_SB_DQS_DP<0>
J 0
(2710 2360);
DISPLAY 0.659574 (2710 2360);
PAINT MONO (2710 2360);
DISPLAY INVISIBLE (2710 2360);
FORCEPROP 1 LASTPIN (2700 2350) BN 0
J 0
(2688 2358);
DISPLAY 0.680851 (2688 2358);
PAINT GREEN (2688 2358);
FORCEPROP 2 LAST CDS_LIB standard
J 0
(2750 2350);
DISPLAY INVISIBLE (2750 2350);
FORCEPROP 1 LAST BODY_TYPE PLUMBING
J 0
(2750 2400);
DISPLAY 0.872340 (2750 2400);
PAINT GREEN (2750 2400);
DISPLAY INVISIBLE (2750 2400);
FORCEPROP 1 LAST HDL_TAP TRUE
J 0
(3075 2225);
DISPLAY 0.872340 (3075 2225);
DISPLAY INVISIBLE (3075 2225);
FORCEPROP 1 LAST PATH I129
J 0
(2748 2350);
DISPLAY 0.872340 (2748 2350);
PAINT GREEN (2748 2350);
DISPLAY INVISIBLE (2748 2350);
FORCEADD TAP..1
R 2
(-675 300);
FORCEPROP 3 LASTPIN (-625 300) SIG_NAME M_C_CPU1_SB_CB<6>
J 0
(-615 310);
DISPLAY 0.659574 (-615 310);
PAINT MONO (-615 310);
DISPLAY INVISIBLE (-615 310);
FORCEPROP 1 LASTPIN (-625 300) BN 6
J 2
(-613 308);
DISPLAY 0.680851 (-613 308);
PAINT GREEN (-613 308);
FORCEPROP 2 LAST CDS_LIB standard
J 0
(-675 300);
DISPLAY INVISIBLE (-675 300);
FORCEPROP 1 LAST BODY_TYPE PLUMBING
J 2
(-675 350);
DISPLAY 0.872340 (-675 350);
PAINT GREEN (-675 350);
DISPLAY INVISIBLE (-675 350);
FORCEPROP 1 LAST HDL_TAP TRUE
J 2
(-1000 175);
DISPLAY 0.872340 (-1000 175);
DISPLAY INVISIBLE (-1000 175);
FORCEPROP 1 LAST PATH I13
J 2
(-673 300);
DISPLAY 0.872340 (-673 300);
PAINT GREEN (-673 300);
DISPLAY INVISIBLE (-673 300);
FORCEADD TAP..1
(2750 2500);
FORCEPROP 3 LASTPIN (2700 2500) SIG_NAME M_C_CPU1_SB_DQS_DP<3>
J 0
(2710 2510);
DISPLAY 0.659574 (2710 2510);
PAINT MONO (2710 2510);
DISPLAY INVISIBLE (2710 2510);
FORCEPROP 1 LASTPIN (2700 2500) BN 3
J 0
(2688 2508);
DISPLAY 0.680851 (2688 2508);
PAINT GREEN (2688 2508);
FORCEPROP 2 LAST CDS_LIB standard
J 0
(2750 2500);
DISPLAY INVISIBLE (2750 2500);
FORCEPROP 1 LAST BODY_TYPE PLUMBING
J 0
(2750 2550);
DISPLAY 0.872340 (2750 2550);
PAINT GREEN (2750 2550);
DISPLAY INVISIBLE (2750 2550);
FORCEPROP 1 LAST HDL_TAP TRUE
J 0
(3075 2375);
DISPLAY 0.872340 (3075 2375);
DISPLAY INVISIBLE (3075 2375);
FORCEPROP 1 LAST PATH I130
J 0
(2748 2500);
DISPLAY 0.872340 (2748 2500);
PAINT GREEN (2748 2500);
DISPLAY INVISIBLE (2748 2500);
FORCEADD TAP..1
(2750 2450);
FORCEPROP 3 LASTPIN (2700 2450) SIG_NAME M_C_CPU1_SB_DQS_DP<2>
J 0
(2710 2460);
DISPLAY 0.659574 (2710 2460);
PAINT MONO (2710 2460);
DISPLAY INVISIBLE (2710 2460);
FORCEPROP 1 LASTPIN (2700 2450) BN 2
J 0
(2688 2458);
DISPLAY 0.680851 (2688 2458);
PAINT GREEN (2688 2458);
FORCEPROP 2 LAST CDS_LIB standard
J 0
(2750 2450);
DISPLAY INVISIBLE (2750 2450);
FORCEPROP 1 LAST BODY_TYPE PLUMBING
J 0
(2750 2500);
DISPLAY 0.872340 (2750 2500);
PAINT GREEN (2750 2500);
DISPLAY INVISIBLE (2750 2500);
FORCEPROP 1 LAST HDL_TAP TRUE
J 0
(3075 2325);
DISPLAY 0.872340 (3075 2325);
DISPLAY INVISIBLE (3075 2325);
FORCEPROP 1 LAST PATH I131
J 0
(2748 2450);
DISPLAY 0.872340 (2748 2450);
PAINT GREEN (2748 2450);
DISPLAY INVISIBLE (2748 2450);
FORCEADD TAP..1
(2750 2400);
FORCEPROP 3 LASTPIN (2700 2400) SIG_NAME M_C_CPU1_SB_DQS_DP<1>
J 0
(2710 2410);
DISPLAY 0.659574 (2710 2410);
PAINT MONO (2710 2410);
DISPLAY INVISIBLE (2710 2410);
FORCEPROP 1 LASTPIN (2700 2400) BN 1
J 0
(2688 2408);
DISPLAY 0.680851 (2688 2408);
PAINT GREEN (2688 2408);
FORCEPROP 2 LAST CDS_LIB standard
J 0
(2750 2400);
DISPLAY INVISIBLE (2750 2400);
FORCEPROP 1 LAST BODY_TYPE PLUMBING
J 0
(2750 2450);
DISPLAY 0.872340 (2750 2450);
PAINT GREEN (2750 2450);
DISPLAY INVISIBLE (2750 2450);
FORCEPROP 1 LAST HDL_TAP TRUE
J 0
(3075 2275);
DISPLAY 0.872340 (3075 2275);
DISPLAY INVISIBLE (3075 2275);
FORCEPROP 1 LAST PATH I132
J 0
(2748 2400);
DISPLAY 0.872340 (2748 2400);
PAINT GREEN (2748 2400);
DISPLAY INVISIBLE (2748 2400);
FORCEADD TAP..1
(2750 2550);
FORCEPROP 3 LASTPIN (2700 2550) SIG_NAME M_C_CPU1_SB_DQS_DP<4>
J 0
(2710 2560);
DISPLAY 0.659574 (2710 2560);
PAINT MONO (2710 2560);
DISPLAY INVISIBLE (2710 2560);
FORCEPROP 1 LASTPIN (2700 2550) BN 4
J 0
(2688 2558);
DISPLAY 0.680851 (2688 2558);
PAINT GREEN (2688 2558);
FORCEPROP 2 LAST CDS_LIB standard
J 0
(2750 2550);
DISPLAY INVISIBLE (2750 2550);
FORCEPROP 1 LAST BODY_TYPE PLUMBING
J 0
(2750 2600);
DISPLAY 0.872340 (2750 2600);
PAINT GREEN (2750 2600);
DISPLAY INVISIBLE (2750 2600);
FORCEPROP 1 LAST HDL_TAP TRUE
J 0
(3075 2425);
DISPLAY 0.872340 (3075 2425);
DISPLAY INVISIBLE (3075 2425);
FORCEPROP 1 LAST PATH I133
J 0
(2748 2550);
DISPLAY 0.872340 (2748 2550);
PAINT GREEN (2748 2550);
DISPLAY INVISIBLE (2748 2550);
FORCEADD TAP..1
(2750 2600);
FORCEPROP 3 LASTPIN (2700 2600) SIG_NAME M_C_CPU1_SB_DQS_DP<5>
J 0
(2710 2610);
DISPLAY 0.659574 (2710 2610);
PAINT MONO (2710 2610);
DISPLAY INVISIBLE (2710 2610);
FORCEPROP 1 LASTPIN (2700 2600) BN 5
J 0
(2688 2608);
DISPLAY 0.680851 (2688 2608);
PAINT GREEN (2688 2608);
FORCEPROP 2 LAST CDS_LIB standard
J 0
(2750 2600);
DISPLAY INVISIBLE (2750 2600);
FORCEPROP 1 LAST BODY_TYPE PLUMBING
J 0
(2750 2650);
DISPLAY 0.872340 (2750 2650);
PAINT GREEN (2750 2650);
DISPLAY INVISIBLE (2750 2650);
FORCEPROP 1 LAST HDL_TAP TRUE
J 0
(3075 2475);
DISPLAY 0.872340 (3075 2475);
DISPLAY INVISIBLE (3075 2475);
FORCEPROP 1 LAST PATH I134
J 0
(2748 2600);
DISPLAY 0.872340 (2748 2600);
PAINT GREEN (2748 2600);
DISPLAY INVISIBLE (2748 2600);
FORCEADD TAP..1
(2750 2650);
FORCEPROP 3 LASTPIN (2700 2650) SIG_NAME M_C_CPU1_SB_DQS_DP<6>
J 0
(2710 2660);
DISPLAY 0.659574 (2710 2660);
PAINT MONO (2710 2660);
DISPLAY INVISIBLE (2710 2660);
FORCEPROP 1 LASTPIN (2700 2650) BN 6
J 0
(2688 2658);
DISPLAY 0.680851 (2688 2658);
PAINT GREEN (2688 2658);
FORCEPROP 2 LAST CDS_LIB standard
J 0
(2750 2650);
DISPLAY INVISIBLE (2750 2650);
FORCEPROP 1 LAST BODY_TYPE PLUMBING
J 0
(2750 2700);
DISPLAY 0.872340 (2750 2700);
PAINT GREEN (2750 2700);
DISPLAY INVISIBLE (2750 2700);
FORCEPROP 1 LAST HDL_TAP TRUE
J 0
(3075 2525);
DISPLAY 0.872340 (3075 2525);
DISPLAY INVISIBLE (3075 2525);
FORCEPROP 1 LAST PATH I135
J 0
(2748 2650);
DISPLAY 0.872340 (2748 2650);
PAINT GREEN (2748 2650);
DISPLAY INVISIBLE (2748 2650);
FORCEADD TAP..1
(2750 2700);
FORCEPROP 3 LASTPIN (2700 2700) SIG_NAME M_C_CPU1_SB_DQS_DP<7>
J 0
(2710 2710);
DISPLAY 0.659574 (2710 2710);
PAINT MONO (2710 2710);
DISPLAY INVISIBLE (2710 2710);
FORCEPROP 1 LASTPIN (2700 2700) BN 7
J 0
(2688 2708);
DISPLAY 0.680851 (2688 2708);
PAINT GREEN (2688 2708);
FORCEPROP 2 LAST CDS_LIB standard
J 0
(2750 2700);
DISPLAY INVISIBLE (2750 2700);
FORCEPROP 1 LAST BODY_TYPE PLUMBING
J 0
(2750 2750);
DISPLAY 0.872340 (2750 2750);
PAINT GREEN (2750 2750);
DISPLAY INVISIBLE (2750 2750);
FORCEPROP 1 LAST HDL_TAP TRUE
J 0
(3075 2575);
DISPLAY 0.872340 (3075 2575);
DISPLAY INVISIBLE (3075 2575);
FORCEPROP 1 LAST PATH I136
J 0
(2748 2700);
DISPLAY 0.872340 (2748 2700);
PAINT GREEN (2748 2700);
DISPLAY INVISIBLE (2748 2700);
FORCEADD TAP..1
(2750 2750);
FORCEPROP 3 LASTPIN (2700 2750) SIG_NAME M_C_CPU1_SB_DQS_DP<8>
J 0
(2710 2760);
DISPLAY 0.659574 (2710 2760);
PAINT MONO (2710 2760);
DISPLAY INVISIBLE (2710 2760);
FORCEPROP 1 LASTPIN (2700 2750) BN 8
J 0
(2688 2758);
DISPLAY 0.680851 (2688 2758);
PAINT GREEN (2688 2758);
FORCEPROP 2 LAST CDS_LIB standard
J 0
(2750 2750);
DISPLAY INVISIBLE (2750 2750);
FORCEPROP 1 LAST BODY_TYPE PLUMBING
J 0
(2750 2800);
DISPLAY 0.872340 (2750 2800);
PAINT GREEN (2750 2800);
DISPLAY INVISIBLE (2750 2800);
FORCEPROP 1 LAST HDL_TAP TRUE
J 0
(3075 2625);
DISPLAY 0.872340 (3075 2625);
DISPLAY INVISIBLE (3075 2625);
FORCEPROP 1 LAST PATH I137
J 0
(2748 2750);
DISPLAY 0.872340 (2748 2750);
PAINT GREEN (2748 2750);
DISPLAY INVISIBLE (2748 2750);
FORCEADD TAP..1
(2750 2800);
FORCEPROP 3 LASTPIN (2700 2800) SIG_NAME M_C_CPU1_SB_DQS_DP<9>
J 0
(2710 2810);
DISPLAY 0.659574 (2710 2810);
PAINT MONO (2710 2810);
DISPLAY INVISIBLE (2710 2810);
FORCEPROP 1 LASTPIN (2700 2800) BN 9
J 0
(2688 2808);
DISPLAY 0.680851 (2688 2808);
PAINT GREEN (2688 2808);
FORCEPROP 2 LAST CDS_LIB standard
J 0
(2750 2800);
DISPLAY INVISIBLE (2750 2800);
FORCEPROP 1 LAST BODY_TYPE PLUMBING
J 0
(2750 2850);
DISPLAY 0.872340 (2750 2850);
PAINT GREEN (2750 2850);
DISPLAY INVISIBLE (2750 2850);
FORCEPROP 1 LAST HDL_TAP TRUE
J 0
(3075 2675);
DISPLAY 0.872340 (3075 2675);
DISPLAY INVISIBLE (3075 2675);
FORCEPROP 1 LAST PATH I138
J 0
(2748 2800);
DISPLAY 0.872340 (2748 2800);
PAINT GREEN (2748 2800);
DISPLAY INVISIBLE (2748 2800);
FORCEADD TAP..1
(2750 2950);
FORCEPROP 3 LASTPIN (2700 2950) SIG_NAME M_C_CPU1_SA_DQS_DN<0>
J 0
(2710 2960);
DISPLAY 0.659574 (2710 2960);
PAINT MONO (2710 2960);
DISPLAY INVISIBLE (2710 2960);
FORCEPROP 1 LASTPIN (2700 2950) BN 0
J 0
(2688 2958);
DISPLAY 0.680851 (2688 2958);
PAINT GREEN (2688 2958);
FORCEPROP 2 LAST CDS_LIB standard
J 0
(2750 2950);
DISPLAY INVISIBLE (2750 2950);
FORCEPROP 1 LAST BODY_TYPE PLUMBING
J 0
(2750 3000);
DISPLAY 0.872340 (2750 3000);
PAINT GREEN (2750 3000);
DISPLAY INVISIBLE (2750 3000);
FORCEPROP 1 LAST HDL_TAP TRUE
J 0
(3075 2825);
DISPLAY 0.872340 (3075 2825);
DISPLAY INVISIBLE (3075 2825);
FORCEPROP 1 LAST PATH I139
J 0
(2748 2950);
DISPLAY 0.872340 (2748 2950);
PAINT GREEN (2748 2950);
DISPLAY INVISIBLE (2748 2950);
FORCEADD OFFPAGE..3
R 2
(-1700 375);
FORCEPROP 2 LAST $XR1 103 
J 0
(-2130 375);
DISPLAY 0.638298 (-2130 375);
PAINT MONO (-2130 375);
FORCEPROP 2 LAST $XR0 102 
J 0
(-2010 375);
DISPLAY 0.638298 (-2010 375);
PAINT MONO (-2010 375);
FORCEPROP 2 LAST CDS_LIB standard
J 0
(-1700 375);
DISPLAY INVISIBLE (-1700 375);
FORCEPROP 1 LAST OFFPAGE TRUE
J 2
(-2025 250);
DISPLAY 0.872340 (-2025 250);
DISPLAY INVISIBLE (-2025 250);
FORCEPROP 1 LAST COMMENT_BODY TRUE
J 2
(-1650 275);
DISPLAY 0.872340 (-1650 275);
PAINT GREEN (-1650 275);
DISPLAY INVISIBLE (-1650 275);
FORCEPROP 2 LAST PATH I14
J 0
(-1650 450);
DISPLAY 1.021277 (-1650 450);
DISPLAY INVISIBLE (-1650 450);
FORCEADD TAP..1
(2750 3000);
FORCEPROP 3 LASTPIN (2700 3000) SIG_NAME M_C_CPU1_SA_DQS_DN<1>
J 0
(2710 3010);
DISPLAY 0.659574 (2710 3010);
PAINT MONO (2710 3010);
DISPLAY INVISIBLE (2710 3010);
FORCEPROP 1 LASTPIN (2700 3000) BN 1
J 0
(2688 3008);
DISPLAY 0.680851 (2688 3008);
PAINT GREEN (2688 3008);
FORCEPROP 2 LAST CDS_LIB standard
J 0
(2750 3000);
DISPLAY INVISIBLE (2750 3000);
FORCEPROP 1 LAST BODY_TYPE PLUMBING
J 0
(2750 3050);
DISPLAY 0.872340 (2750 3050);
PAINT GREEN (2750 3050);
DISPLAY INVISIBLE (2750 3050);
FORCEPROP 1 LAST HDL_TAP TRUE
J 0
(3075 2875);
DISPLAY 0.872340 (3075 2875);
DISPLAY INVISIBLE (3075 2875);
FORCEPROP 1 LAST PATH I140
J 0
(2748 3000);
DISPLAY 0.872340 (2748 3000);
PAINT GREEN (2748 3000);
DISPLAY INVISIBLE (2748 3000);
FORCEADD TAP..1
(2750 3100);
FORCEPROP 3 LASTPIN (2700 3100) SIG_NAME M_C_CPU1_SA_DQS_DN<3>
J 0
(2710 3110);
DISPLAY 0.659574 (2710 3110);
PAINT MONO (2710 3110);
DISPLAY INVISIBLE (2710 3110);
FORCEPROP 1 LASTPIN (2700 3100) BN 3
J 0
(2688 3108);
DISPLAY 0.680851 (2688 3108);
PAINT GREEN (2688 3108);
FORCEPROP 2 LAST CDS_LIB standard
J 0
(2750 3100);
DISPLAY INVISIBLE (2750 3100);
FORCEPROP 1 LAST BODY_TYPE PLUMBING
J 0
(2750 3150);
DISPLAY 0.872340 (2750 3150);
PAINT GREEN (2750 3150);
DISPLAY INVISIBLE (2750 3150);
FORCEPROP 1 LAST HDL_TAP TRUE
J 0
(3075 2975);
DISPLAY 0.872340 (3075 2975);
DISPLAY INVISIBLE (3075 2975);
FORCEPROP 1 LAST PATH I141
J 0
(2748 3100);
DISPLAY 0.872340 (2748 3100);
PAINT GREEN (2748 3100);
DISPLAY INVISIBLE (2748 3100);
FORCEADD TAP..1
(2750 3050);
FORCEPROP 3 LASTPIN (2700 3050) SIG_NAME M_C_CPU1_SA_DQS_DN<2>
J 0
(2710 3060);
DISPLAY 0.659574 (2710 3060);
PAINT MONO (2710 3060);
DISPLAY INVISIBLE (2710 3060);
FORCEPROP 1 LASTPIN (2700 3050) BN 2
J 0
(2688 3058);
DISPLAY 0.680851 (2688 3058);
PAINT GREEN (2688 3058);
FORCEPROP 2 LAST CDS_LIB standard
J 0
(2750 3050);
DISPLAY INVISIBLE (2750 3050);
FORCEPROP 1 LAST BODY_TYPE PLUMBING
J 0
(2750 3100);
DISPLAY 0.872340 (2750 3100);
PAINT GREEN (2750 3100);
DISPLAY INVISIBLE (2750 3100);
FORCEPROP 1 LAST HDL_TAP TRUE
J 0
(3075 2925);
DISPLAY 0.872340 (3075 2925);
DISPLAY INVISIBLE (3075 2925);
FORCEPROP 1 LAST PATH I142
J 0
(2748 3050);
DISPLAY 0.872340 (2748 3050);
PAINT GREEN (2748 3050);
DISPLAY INVISIBLE (2748 3050);
FORCEADD TAP..1
(2750 3150);
FORCEPROP 3 LASTPIN (2700 3150) SIG_NAME M_C_CPU1_SA_DQS_DN<4>
J 0
(2710 3160);
DISPLAY 0.659574 (2710 3160);
PAINT MONO (2710 3160);
DISPLAY INVISIBLE (2710 3160);
FORCEPROP 1 LASTPIN (2700 3150) BN 4
J 0
(2688 3158);
DISPLAY 0.680851 (2688 3158);
PAINT GREEN (2688 3158);
FORCEPROP 2 LAST CDS_LIB standard
J 0
(2750 3150);
DISPLAY INVISIBLE (2750 3150);
FORCEPROP 1 LAST BODY_TYPE PLUMBING
J 0
(2750 3200);
DISPLAY 0.872340 (2750 3200);
PAINT GREEN (2750 3200);
DISPLAY INVISIBLE (2750 3200);
FORCEPROP 1 LAST HDL_TAP TRUE
J 0
(3075 3025);
DISPLAY 0.872340 (3075 3025);
DISPLAY INVISIBLE (3075 3025);
FORCEPROP 1 LAST PATH I143
J 0
(2748 3150);
DISPLAY 0.872340 (2748 3150);
PAINT GREEN (2748 3150);
DISPLAY INVISIBLE (2748 3150);
FORCEADD TAP..1
(2750 3200);
FORCEPROP 3 LASTPIN (2700 3200) SIG_NAME M_C_CPU1_SA_DQS_DN<5>
J 0
(2710 3210);
DISPLAY 0.659574 (2710 3210);
PAINT MONO (2710 3210);
DISPLAY INVISIBLE (2710 3210);
FORCEPROP 1 LASTPIN (2700 3200) BN 5
J 0
(2688 3208);
DISPLAY 0.680851 (2688 3208);
PAINT GREEN (2688 3208);
FORCEPROP 2 LAST CDS_LIB standard
J 0
(2750 3200);
DISPLAY INVISIBLE (2750 3200);
FORCEPROP 1 LAST BODY_TYPE PLUMBING
J 0
(2750 3250);
DISPLAY 0.872340 (2750 3250);
PAINT GREEN (2750 3250);
DISPLAY INVISIBLE (2750 3250);
FORCEPROP 1 LAST HDL_TAP TRUE
J 0
(3075 3075);
DISPLAY 0.872340 (3075 3075);
DISPLAY INVISIBLE (3075 3075);
FORCEPROP 1 LAST PATH I144
J 0
(2748 3200);
DISPLAY 0.872340 (2748 3200);
PAINT GREEN (2748 3200);
DISPLAY INVISIBLE (2748 3200);
FORCEADD TAP..1
(2750 3250);
FORCEPROP 3 LASTPIN (2700 3250) SIG_NAME M_C_CPU1_SA_DQS_DN<6>
J 0
(2710 3260);
DISPLAY 0.659574 (2710 3260);
PAINT MONO (2710 3260);
DISPLAY INVISIBLE (2710 3260);
FORCEPROP 1 LASTPIN (2700 3250) BN 6
J 0
(2688 3258);
DISPLAY 0.680851 (2688 3258);
PAINT GREEN (2688 3258);
FORCEPROP 2 LAST CDS_LIB standard
J 0
(2750 3250);
DISPLAY INVISIBLE (2750 3250);
FORCEPROP 1 LAST BODY_TYPE PLUMBING
J 0
(2750 3300);
DISPLAY 0.872340 (2750 3300);
PAINT GREEN (2750 3300);
DISPLAY INVISIBLE (2750 3300);
FORCEPROP 1 LAST HDL_TAP TRUE
J 0
(3075 3125);
DISPLAY 0.872340 (3075 3125);
DISPLAY INVISIBLE (3075 3125);
FORCEPROP 1 LAST PATH I145
J 0
(2748 3250);
DISPLAY 0.872340 (2748 3250);
PAINT GREEN (2748 3250);
DISPLAY INVISIBLE (2748 3250);
FORCEADD TAP..1
(2750 3350);
FORCEPROP 3 LASTPIN (2700 3350) SIG_NAME M_C_CPU1_SA_DQS_DN<8>
J 0
(2710 3360);
DISPLAY 0.659574 (2710 3360);
PAINT MONO (2710 3360);
DISPLAY INVISIBLE (2710 3360);
FORCEPROP 1 LASTPIN (2700 3350) BN 8
J 0
(2688 3358);
DISPLAY 0.680851 (2688 3358);
PAINT GREEN (2688 3358);
FORCEPROP 2 LAST CDS_LIB standard
J 0
(2750 3350);
DISPLAY INVISIBLE (2750 3350);
FORCEPROP 1 LAST BODY_TYPE PLUMBING
J 0
(2750 3400);
DISPLAY 0.872340 (2750 3400);
PAINT GREEN (2750 3400);
DISPLAY INVISIBLE (2750 3400);
FORCEPROP 1 LAST HDL_TAP TRUE
J 0
(3075 3225);
DISPLAY 0.872340 (3075 3225);
DISPLAY INVISIBLE (3075 3225);
FORCEPROP 1 LAST PATH I146
J 0
(2748 3350);
DISPLAY 0.872340 (2748 3350);
PAINT GREEN (2748 3350);
DISPLAY INVISIBLE (2748 3350);
FORCEADD TAP..1
(2750 3300);
FORCEPROP 3 LASTPIN (2700 3300) SIG_NAME M_C_CPU1_SA_DQS_DN<7>
J 0
(2710 3310);
DISPLAY 0.659574 (2710 3310);
PAINT MONO (2710 3310);
DISPLAY INVISIBLE (2710 3310);
FORCEPROP 1 LASTPIN (2700 3300) BN 7
J 0
(2688 3308);
DISPLAY 0.680851 (2688 3308);
PAINT GREEN (2688 3308);
FORCEPROP 2 LAST CDS_LIB standard
J 0
(2750 3300);
DISPLAY INVISIBLE (2750 3300);
FORCEPROP 1 LAST BODY_TYPE PLUMBING
J 0
(2750 3350);
DISPLAY 0.872340 (2750 3350);
PAINT GREEN (2750 3350);
DISPLAY INVISIBLE (2750 3350);
FORCEPROP 1 LAST HDL_TAP TRUE
J 0
(3075 3175);
DISPLAY 0.872340 (3075 3175);
DISPLAY INVISIBLE (3075 3175);
FORCEPROP 1 LAST PATH I147
J 0
(2748 3300);
DISPLAY 0.872340 (2748 3300);
PAINT GREEN (2748 3300);
DISPLAY INVISIBLE (2748 3300);
FORCEADD TAP..1
(2750 3500);
FORCEPROP 3 LASTPIN (2700 3500) SIG_NAME M_C_CPU1_SA_DQS_DP<0>
J 0
(2710 3510);
DISPLAY 0.659574 (2710 3510);
PAINT MONO (2710 3510);
DISPLAY INVISIBLE (2710 3510);
FORCEPROP 1 LASTPIN (2700 3500) BN 0
J 0
(2688 3508);
DISPLAY 0.680851 (2688 3508);
PAINT GREEN (2688 3508);
FORCEPROP 2 LAST CDS_LIB standard
J 0
(2750 3500);
DISPLAY INVISIBLE (2750 3500);
FORCEPROP 1 LAST BODY_TYPE PLUMBING
J 0
(2750 3550);
DISPLAY 0.872340 (2750 3550);
PAINT GREEN (2750 3550);
DISPLAY INVISIBLE (2750 3550);
FORCEPROP 1 LAST HDL_TAP TRUE
J 0
(3075 3375);
DISPLAY 0.872340 (3075 3375);
DISPLAY INVISIBLE (3075 3375);
FORCEPROP 1 LAST PATH I148
J 0
(2748 3500);
DISPLAY 0.872340 (2748 3500);
PAINT GREEN (2748 3500);
DISPLAY INVISIBLE (2748 3500);
FORCEADD TAP..1
(2750 3400);
FORCEPROP 3 LASTPIN (2700 3400) SIG_NAME M_C_CPU1_SA_DQS_DN<9>
J 0
(2710 3410);
DISPLAY 0.659574 (2710 3410);
PAINT MONO (2710 3410);
DISPLAY INVISIBLE (2710 3410);
FORCEPROP 1 LASTPIN (2700 3400) BN 9
J 0
(2688 3408);
DISPLAY 0.680851 (2688 3408);
PAINT GREEN (2688 3408);
FORCEPROP 2 LAST CDS_LIB standard
J 0
(2750 3400);
DISPLAY INVISIBLE (2750 3400);
FORCEPROP 1 LAST BODY_TYPE PLUMBING
J 0
(2750 3450);
DISPLAY 0.872340 (2750 3450);
PAINT GREEN (2750 3450);
DISPLAY INVISIBLE (2750 3450);
FORCEPROP 1 LAST HDL_TAP TRUE
J 0
(3075 3275);
DISPLAY 0.872340 (3075 3275);
DISPLAY INVISIBLE (3075 3275);
FORCEPROP 1 LAST PATH I149
J 0
(2748 3400);
DISPLAY 0.872340 (2748 3400);
PAINT GREEN (2748 3400);
DISPLAY INVISIBLE (2748 3400);
FORCEADD OFFPAGE..3
R 2
(-1700 1975);
FORCEPROP 2 LAST $XR1 103 
J 0
(-2130 1975);
DISPLAY 0.638298 (-2130 1975);
PAINT MONO (-2130 1975);
FORCEPROP 2 LAST $XR0 102 
J 0
(-2010 1975);
DISPLAY 0.638298 (-2010 1975);
PAINT MONO (-2010 1975);
FORCEPROP 2 LAST CDS_LIB standard
J 0
(-1700 1975);
DISPLAY INVISIBLE (-1700 1975);
FORCEPROP 1 LAST OFFPAGE TRUE
J 2
(-2025 1850);
DISPLAY 0.872340 (-2025 1850);
DISPLAY INVISIBLE (-2025 1850);
FORCEPROP 1 LAST COMMENT_BODY TRUE
J 2
(-1650 1875);
DISPLAY 0.872340 (-1650 1875);
PAINT GREEN (-1650 1875);
DISPLAY INVISIBLE (-1650 1875);
FORCEPROP 2 LAST PATH I15
J 0
(-1650 2050);
DISPLAY 1.021277 (-1650 2050);
DISPLAY INVISIBLE (-1650 2050);
FORCEADD TAP..1
(2750 3650);
FORCEPROP 3 LASTPIN (2700 3650) SIG_NAME M_C_CPU1_SA_DQS_DP<3>
J 0
(2710 3660);
DISPLAY 0.659574 (2710 3660);
PAINT MONO (2710 3660);
DISPLAY INVISIBLE (2710 3660);
FORCEPROP 1 LASTPIN (2700 3650) BN 3
J 0
(2688 3658);
DISPLAY 0.680851 (2688 3658);
PAINT GREEN (2688 3658);
FORCEPROP 2 LAST CDS_LIB standard
J 0
(2750 3650);
DISPLAY INVISIBLE (2750 3650);
FORCEPROP 1 LAST BODY_TYPE PLUMBING
J 0
(2750 3700);
DISPLAY 0.872340 (2750 3700);
PAINT GREEN (2750 3700);
DISPLAY INVISIBLE (2750 3700);
FORCEPROP 1 LAST HDL_TAP TRUE
J 0
(3075 3525);
DISPLAY 0.872340 (3075 3525);
DISPLAY INVISIBLE (3075 3525);
FORCEPROP 1 LAST PATH I150
J 0
(2748 3650);
DISPLAY 0.872340 (2748 3650);
PAINT GREEN (2748 3650);
DISPLAY INVISIBLE (2748 3650);
FORCEADD TAP..1
(2750 3600);
FORCEPROP 3 LASTPIN (2700 3600) SIG_NAME M_C_CPU1_SA_DQS_DP<2>
J 0
(2710 3610);
DISPLAY 0.659574 (2710 3610);
PAINT MONO (2710 3610);
DISPLAY INVISIBLE (2710 3610);
FORCEPROP 1 LASTPIN (2700 3600) BN 2
J 0
(2688 3608);
DISPLAY 0.680851 (2688 3608);
PAINT GREEN (2688 3608);
FORCEPROP 2 LAST CDS_LIB standard
J 0
(2750 3600);
DISPLAY INVISIBLE (2750 3600);
FORCEPROP 1 LAST BODY_TYPE PLUMBING
J 0
(2750 3650);
DISPLAY 0.872340 (2750 3650);
PAINT GREEN (2750 3650);
DISPLAY INVISIBLE (2750 3650);
FORCEPROP 1 LAST HDL_TAP TRUE
J 0
(3075 3475);
DISPLAY 0.872340 (3075 3475);
DISPLAY INVISIBLE (3075 3475);
FORCEPROP 1 LAST PATH I151
J 0
(2748 3600);
DISPLAY 0.872340 (2748 3600);
PAINT GREEN (2748 3600);
DISPLAY INVISIBLE (2748 3600);
FORCEADD TAP..1
(2750 3550);
FORCEPROP 3 LASTPIN (2700 3550) SIG_NAME M_C_CPU1_SA_DQS_DP<1>
J 0
(2710 3560);
DISPLAY 0.659574 (2710 3560);
PAINT MONO (2710 3560);
DISPLAY INVISIBLE (2710 3560);
FORCEPROP 1 LASTPIN (2700 3550) BN 1
J 0
(2688 3558);
DISPLAY 0.680851 (2688 3558);
PAINT GREEN (2688 3558);
FORCEPROP 2 LAST CDS_LIB standard
J 0
(2750 3550);
DISPLAY INVISIBLE (2750 3550);
FORCEPROP 1 LAST BODY_TYPE PLUMBING
J 0
(2750 3600);
DISPLAY 0.872340 (2750 3600);
PAINT GREEN (2750 3600);
DISPLAY INVISIBLE (2750 3600);
FORCEPROP 1 LAST HDL_TAP TRUE
J 0
(3075 3425);
DISPLAY 0.872340 (3075 3425);
DISPLAY INVISIBLE (3075 3425);
FORCEPROP 1 LAST PATH I152
J 0
(2748 3550);
DISPLAY 0.872340 (2748 3550);
PAINT GREEN (2748 3550);
DISPLAY INVISIBLE (2748 3550);
FORCEADD TAP..1
(2750 3750);
FORCEPROP 3 LASTPIN (2700 3750) SIG_NAME M_C_CPU1_SA_DQS_DP<5>
J 0
(2710 3760);
DISPLAY 0.659574 (2710 3760);
PAINT MONO (2710 3760);
DISPLAY INVISIBLE (2710 3760);
FORCEPROP 1 LASTPIN (2700 3750) BN 5
J 0
(2688 3758);
DISPLAY 0.680851 (2688 3758);
PAINT GREEN (2688 3758);
FORCEPROP 2 LAST CDS_LIB standard
J 0
(2750 3750);
DISPLAY INVISIBLE (2750 3750);
FORCEPROP 1 LAST BODY_TYPE PLUMBING
J 0
(2750 3800);
DISPLAY 0.872340 (2750 3800);
PAINT GREEN (2750 3800);
DISPLAY INVISIBLE (2750 3800);
FORCEPROP 1 LAST HDL_TAP TRUE
J 0
(3075 3625);
DISPLAY 0.872340 (3075 3625);
DISPLAY INVISIBLE (3075 3625);
FORCEPROP 1 LAST PATH I153
J 0
(2748 3750);
DISPLAY 0.872340 (2748 3750);
PAINT GREEN (2748 3750);
DISPLAY INVISIBLE (2748 3750);
FORCEADD TAP..1
(2750 3700);
FORCEPROP 3 LASTPIN (2700 3700) SIG_NAME M_C_CPU1_SA_DQS_DP<4>
J 0
(2710 3710);
DISPLAY 0.659574 (2710 3710);
PAINT MONO (2710 3710);
DISPLAY INVISIBLE (2710 3710);
FORCEPROP 1 LASTPIN (2700 3700) BN 4
J 0
(2688 3708);
DISPLAY 0.680851 (2688 3708);
PAINT GREEN (2688 3708);
FORCEPROP 2 LAST CDS_LIB standard
J 0
(2750 3700);
DISPLAY INVISIBLE (2750 3700);
FORCEPROP 1 LAST BODY_TYPE PLUMBING
J 0
(2750 3750);
DISPLAY 0.872340 (2750 3750);
PAINT GREEN (2750 3750);
DISPLAY INVISIBLE (2750 3750);
FORCEPROP 1 LAST HDL_TAP TRUE
J 0
(3075 3575);
DISPLAY 0.872340 (3075 3575);
DISPLAY INVISIBLE (3075 3575);
FORCEPROP 1 LAST PATH I154
J 0
(2748 3700);
DISPLAY 0.872340 (2748 3700);
PAINT GREEN (2748 3700);
DISPLAY INVISIBLE (2748 3700);
FORCEADD TAP..1
(2750 3850);
FORCEPROP 3 LASTPIN (2700 3850) SIG_NAME M_C_CPU1_SA_DQS_DP<7>
J 0
(2710 3860);
DISPLAY 0.659574 (2710 3860);
PAINT MONO (2710 3860);
DISPLAY INVISIBLE (2710 3860);
FORCEPROP 1 LASTPIN (2700 3850) BN 7
J 0
(2688 3858);
DISPLAY 0.680851 (2688 3858);
PAINT GREEN (2688 3858);
FORCEPROP 2 LAST CDS_LIB standard
J 0
(2750 3850);
DISPLAY INVISIBLE (2750 3850);
FORCEPROP 1 LAST BODY_TYPE PLUMBING
J 0
(2750 3900);
DISPLAY 0.872340 (2750 3900);
PAINT GREEN (2750 3900);
DISPLAY INVISIBLE (2750 3900);
FORCEPROP 1 LAST HDL_TAP TRUE
J 0
(3075 3725);
DISPLAY 0.872340 (3075 3725);
DISPLAY INVISIBLE (3075 3725);
FORCEPROP 1 LAST PATH I155
J 0
(2748 3850);
DISPLAY 0.872340 (2748 3850);
PAINT GREEN (2748 3850);
DISPLAY INVISIBLE (2748 3850);
FORCEADD TAP..1
(2750 3900);
FORCEPROP 3 LASTPIN (2700 3900) SIG_NAME M_C_CPU1_SA_DQS_DP<8>
J 0
(2710 3910);
DISPLAY 0.659574 (2710 3910);
PAINT MONO (2710 3910);
DISPLAY INVISIBLE (2710 3910);
FORCEPROP 1 LASTPIN (2700 3900) BN 8
J 0
(2688 3908);
DISPLAY 0.680851 (2688 3908);
PAINT GREEN (2688 3908);
FORCEPROP 2 LAST CDS_LIB standard
J 0
(2750 3900);
DISPLAY INVISIBLE (2750 3900);
FORCEPROP 1 LAST BODY_TYPE PLUMBING
J 0
(2750 3950);
DISPLAY 0.872340 (2750 3950);
PAINT GREEN (2750 3950);
DISPLAY INVISIBLE (2750 3950);
FORCEPROP 1 LAST HDL_TAP TRUE
J 0
(3075 3775);
DISPLAY 0.872340 (3075 3775);
DISPLAY INVISIBLE (3075 3775);
FORCEPROP 1 LAST PATH I156
J 0
(2748 3900);
DISPLAY 0.872340 (2748 3900);
PAINT GREEN (2748 3900);
DISPLAY INVISIBLE (2748 3900);
FORCEADD TAP..1
(2750 3800);
FORCEPROP 3 LASTPIN (2700 3800) SIG_NAME M_C_CPU1_SA_DQS_DP<6>
J 0
(2710 3810);
DISPLAY 0.659574 (2710 3810);
PAINT MONO (2710 3810);
DISPLAY INVISIBLE (2710 3810);
FORCEPROP 1 LASTPIN (2700 3800) BN 6
J 0
(2688 3808);
DISPLAY 0.680851 (2688 3808);
PAINT GREEN (2688 3808);
FORCEPROP 2 LAST CDS_LIB standard
J 0
(2750 3800);
DISPLAY INVISIBLE (2750 3800);
FORCEPROP 1 LAST BODY_TYPE PLUMBING
J 0
(2750 3850);
DISPLAY 0.872340 (2750 3850);
PAINT GREEN (2750 3850);
DISPLAY INVISIBLE (2750 3850);
FORCEPROP 1 LAST HDL_TAP TRUE
J 0
(3075 3675);
DISPLAY 0.872340 (3075 3675);
DISPLAY INVISIBLE (3075 3675);
FORCEPROP 1 LAST PATH I157
J 0
(2748 3800);
DISPLAY 0.872340 (2748 3800);
PAINT GREEN (2748 3800);
DISPLAY INVISIBLE (2748 3800);
FORCEADD TAP..1
(2750 3950);
FORCEPROP 3 LASTPIN (2700 3950) SIG_NAME M_C_CPU1_SA_DQS_DP<9>
J 0
(2710 3960);
DISPLAY 0.659574 (2710 3960);
PAINT MONO (2710 3960);
DISPLAY INVISIBLE (2710 3960);
FORCEPROP 1 LASTPIN (2700 3950) BN 9
J 0
(2688 3958);
DISPLAY 0.680851 (2688 3958);
PAINT GREEN (2688 3958);
FORCEPROP 2 LAST CDS_LIB standard
J 0
(2750 3950);
DISPLAY INVISIBLE (2750 3950);
FORCEPROP 1 LAST BODY_TYPE PLUMBING
J 0
(2750 4000);
DISPLAY 0.872340 (2750 4000);
PAINT GREEN (2750 4000);
DISPLAY INVISIBLE (2750 4000);
FORCEPROP 1 LAST HDL_TAP TRUE
J 0
(3075 3825);
DISPLAY 0.872340 (3075 3825);
DISPLAY INVISIBLE (3075 3825);
FORCEPROP 1 LAST PATH I158
J 0
(2748 3950);
DISPLAY 0.872340 (2748 3950);
PAINT GREEN (2748 3950);
DISPLAY INVISIBLE (2748 3950);
FORCEADD OFFPAGE..2
(3850 375);
FORCEPROP 2 LAST $XR1 103 
J 0
(4159 375);
DISPLAY 0.638298 (4159 375);
PAINT MONO (4159 375);
FORCEPROP 2 LAST $XR0 102 
J 0
(4039 375);
DISPLAY 0.638298 (4039 375);
PAINT MONO (4039 375);
FORCEPROP 2 LAST CDS_LIB standard
J 0
(3850 375);
PAINT MONO (3850 375);
DISPLAY INVISIBLE (3850 375);
FORCEPROP 1 LAST OFFPAGE TRUE
J 0
(4175 250);
DISPLAY 1.170213 (4175 250);
PAINT GREEN (4175 250);
DISPLAY INVISIBLE (4175 250);
FORCEPROP 1 LAST COMMENT_BODY TRUE
J 0
(3805 280);
DISPLAY 1.170213 (3805 280);
PAINT GREEN (3805 280);
DISPLAY INVISIBLE (3805 280);
FORCEPROP 2 LAST PATH I159
J 0
(4025 450);
DISPLAY 1.021277 (4025 450);
DISPLAY INVISIBLE (4025 450);
FORCEADD OFFPAGE..3
R 2
(-1700 2375);
FORCEPROP 2 LAST $XR1 103 
J 0
(-2130 2375);
DISPLAY 0.638298 (-2130 2375);
PAINT MONO (-2130 2375);
FORCEPROP 2 LAST $XR0 102 
J 0
(-2010 2375);
DISPLAY 0.638298 (-2010 2375);
PAINT MONO (-2010 2375);
FORCEPROP 2 LAST CDS_LIB standard
J 0
(-1700 2375);
DISPLAY INVISIBLE (-1700 2375);
FORCEPROP 1 LAST OFFPAGE TRUE
J 2
(-2025 2250);
DISPLAY 0.872340 (-2025 2250);
DISPLAY INVISIBLE (-2025 2250);
FORCEPROP 1 LAST COMMENT_BODY TRUE
J 2
(-1650 2275);
DISPLAY 0.872340 (-1650 2275);
PAINT GREEN (-1650 2275);
DISPLAY INVISIBLE (-1650 2275);
FORCEPROP 2 LAST PATH I16
J 0
(-1650 2450);
DISPLAY 1.021277 (-1650 2450);
DISPLAY INVISIBLE (-1650 2450);
FORCEADD OFFPAGE..2
(3850 675);
FORCEPROP 2 LAST $XR1 103 
J 0
(4159 675);
DISPLAY 0.638298 (4159 675);
PAINT MONO (4159 675);
FORCEPROP 2 LAST $XR0 102 
J 0
(4039 675);
DISPLAY 0.638298 (4039 675);
PAINT MONO (4039 675);
FORCEPROP 2 LAST CDS_LIB standard
J 0
(3850 675);
PAINT MONO (3850 675);
DISPLAY INVISIBLE (3850 675);
FORCEPROP 1 LAST OFFPAGE TRUE
J 0
(4175 550);
DISPLAY 1.170213 (4175 550);
PAINT GREEN (4175 550);
DISPLAY INVISIBLE (4175 550);
FORCEPROP 1 LAST COMMENT_BODY TRUE
J 0
(3805 580);
DISPLAY 1.170213 (3805 580);
PAINT GREEN (3805 580);
DISPLAY INVISIBLE (3805 580);
FORCEPROP 2 LAST PATH I160
J 0
(4025 750);
DISPLAY 1.021277 (4025 750);
DISPLAY INVISIBLE (4025 750);
FORCEADD OFFPAGE..2
(3850 800);
FORCEPROP 2 LAST $XR1 103 
J 0
(4159 800);
DISPLAY 0.638298 (4159 800);
PAINT MONO (4159 800);
FORCEPROP 2 LAST $XR0 102 
J 0
(4039 800);
DISPLAY 0.638298 (4039 800);
PAINT MONO (4039 800);
FORCEPROP 2 LAST CDS_LIB standard
J 0
(3850 800);
PAINT MONO (3850 800);
DISPLAY INVISIBLE (3850 800);
FORCEPROP 1 LAST OFFPAGE TRUE
J 0
(4175 675);
DISPLAY 1.170213 (4175 675);
PAINT GREEN (4175 675);
DISPLAY INVISIBLE (4175 675);
FORCEPROP 1 LAST COMMENT_BODY TRUE
J 0
(3805 705);
DISPLAY 1.170213 (3805 705);
PAINT GREEN (3805 705);
DISPLAY INVISIBLE (3805 705);
FORCEPROP 2 LAST PATH I161
J 0
(4025 875);
DISPLAY 1.021277 (4025 875);
DISPLAY INVISIBLE (4025 875);
FORCEADD OFFPAGE..3
(3850 1175);
FORCEPROP 2 LAST $XR1 103 
J 0
(4184 1175);
DISPLAY 0.638298 (4184 1175);
PAINT MONO (4184 1175);
FORCEPROP 2 LAST $XR0 102 
J 0
(4064 1175);
DISPLAY 0.638298 (4064 1175);
PAINT MONO (4064 1175);
FORCEPROP 2 LAST CDS_LIB standard
J 2
(3850 1175);
DISPLAY INVISIBLE (3850 1175);
FORCEPROP 1 LAST OFFPAGE TRUE
J 0
(4175 1050);
DISPLAY 0.872340 (4175 1050);
DISPLAY INVISIBLE (4175 1050);
FORCEPROP 1 LAST COMMENT_BODY TRUE
J 0
(3800 1075);
DISPLAY 0.872340 (3800 1075);
PAINT GREEN (3800 1075);
DISPLAY INVISIBLE (3800 1075);
FORCEPROP 2 LAST PATH I162
J 0
(4050 1250);
DISPLAY 1.021277 (4050 1250);
DISPLAY INVISIBLE (4050 1250);
FORCEADD OFFPAGE..2
(3850 1300);
FORCEPROP 2 LAST $XR1 103 
J 0
(4159 1300);
DISPLAY 0.638298 (4159 1300);
PAINT MONO (4159 1300);
FORCEPROP 2 LAST $XR0 102 
J 0
(4039 1300);
DISPLAY 0.638298 (4039 1300);
PAINT MONO (4039 1300);
FORCEPROP 2 LAST CDS_LIB standard
J 0
(3850 1300);
PAINT MONO (3850 1300);
DISPLAY INVISIBLE (3850 1300);
FORCEPROP 1 LAST OFFPAGE TRUE
J 0
(4175 1175);
DISPLAY 1.170213 (4175 1175);
PAINT GREEN (4175 1175);
DISPLAY INVISIBLE (4175 1175);
FORCEPROP 1 LAST COMMENT_BODY TRUE
J 0
(3805 1205);
DISPLAY 1.170213 (3805 1205);
PAINT GREEN (3805 1205);
DISPLAY INVISIBLE (3805 1205);
FORCEPROP 2 LAST PATH I163
J 0
(4025 1375);
DISPLAY 1.021277 (4025 1375);
DISPLAY INVISIBLE (4025 1375);
FORCEADD OFFPAGE..3
(3850 1675);
FORCEPROP 2 LAST $XR1 103 
J 0
(4184 1675);
DISPLAY 0.638298 (4184 1675);
PAINT MONO (4184 1675);
FORCEPROP 2 LAST $XR0 102 
J 0
(4064 1675);
DISPLAY 0.638298 (4064 1675);
PAINT MONO (4064 1675);
FORCEPROP 2 LAST CDS_LIB standard
J 2
(3850 1675);
DISPLAY INVISIBLE (3850 1675);
FORCEPROP 1 LAST OFFPAGE TRUE
J 0
(4175 1550);
DISPLAY 0.872340 (4175 1550);
DISPLAY INVISIBLE (4175 1550);
FORCEPROP 1 LAST COMMENT_BODY TRUE
J 0
(3800 1575);
DISPLAY 0.872340 (3800 1575);
PAINT GREEN (3800 1575);
DISPLAY INVISIBLE (3800 1575);
FORCEPROP 2 LAST PATH I164
J 0
(4050 1750);
DISPLAY 1.021277 (4050 1750);
DISPLAY INVISIBLE (4050 1750);
FORCEADD OFFPAGE..3
(3850 2275);
FORCEPROP 2 LAST $XR1 103 
J 0
(4184 2275);
DISPLAY 0.638298 (4184 2275);
PAINT MONO (4184 2275);
FORCEPROP 2 LAST $XR0 102 
J 0
(4064 2275);
DISPLAY 0.638298 (4064 2275);
PAINT MONO (4064 2275);
FORCEPROP 2 LAST CDS_LIB standard
J 2
(3850 2275);
DISPLAY INVISIBLE (3850 2275);
FORCEPROP 1 LAST OFFPAGE TRUE
J 0
(4175 2150);
DISPLAY 0.872340 (4175 2150);
DISPLAY INVISIBLE (4175 2150);
FORCEPROP 1 LAST COMMENT_BODY TRUE
J 0
(3800 2175);
DISPLAY 0.872340 (3800 2175);
PAINT GREEN (3800 2175);
DISPLAY INVISIBLE (3800 2175);
FORCEPROP 2 LAST PATH I165
J 0
(4050 2350);
DISPLAY 1.021277 (4050 2350);
DISPLAY INVISIBLE (4050 2350);
FORCEADD OFFPAGE..3
(3850 2825);
FORCEPROP 2 LAST $XR1 103 
J 0
(4184 2825);
DISPLAY 0.638298 (4184 2825);
PAINT MONO (4184 2825);
FORCEPROP 2 LAST $XR0 102 
J 0
(4064 2825);
DISPLAY 0.638298 (4064 2825);
PAINT MONO (4064 2825);
FORCEPROP 2 LAST CDS_LIB standard
J 2
(3850 2825);
DISPLAY INVISIBLE (3850 2825);
FORCEPROP 1 LAST OFFPAGE TRUE
J 0
(4175 2700);
DISPLAY 0.872340 (4175 2700);
DISPLAY INVISIBLE (4175 2700);
FORCEPROP 1 LAST COMMENT_BODY TRUE
J 0
(3800 2725);
DISPLAY 0.872340 (3800 2725);
PAINT GREEN (3800 2725);
DISPLAY INVISIBLE (3800 2725);
FORCEPROP 2 LAST PATH I166
J 0
(4050 2900);
DISPLAY 1.021277 (4050 2900);
DISPLAY INVISIBLE (4050 2900);
FORCEADD OFFPAGE..3
(3850 3425);
FORCEPROP 2 LAST $XR1 103 
J 0
(4184 3425);
DISPLAY 0.638298 (4184 3425);
PAINT MONO (4184 3425);
FORCEPROP 2 LAST $XR0 102 
J 0
(4064 3425);
DISPLAY 0.638298 (4064 3425);
PAINT MONO (4064 3425);
FORCEPROP 2 LAST CDS_LIB standard
J 2
(3850 3425);
DISPLAY INVISIBLE (3850 3425);
FORCEPROP 1 LAST OFFPAGE TRUE
J 0
(4175 3300);
DISPLAY 0.872340 (4175 3300);
DISPLAY INVISIBLE (4175 3300);
FORCEPROP 1 LAST COMMENT_BODY TRUE
J 0
(3800 3325);
DISPLAY 0.872340 (3800 3325);
PAINT GREEN (3800 3325);
DISPLAY INVISIBLE (3800 3325);
FORCEPROP 2 LAST PATH I167
J 0
(4050 3500);
DISPLAY 1.021277 (4050 3500);
DISPLAY INVISIBLE (4050 3500);
FORCEADD OFFPAGE..3
(3850 3975);
FORCEPROP 2 LAST $XR1 103 
J 0
(4184 3975);
DISPLAY 0.638298 (4184 3975);
PAINT MONO (4184 3975);
FORCEPROP 2 LAST $XR0 102 
J 0
(4064 3975);
DISPLAY 0.638298 (4064 3975);
PAINT MONO (4064 3975);
FORCEPROP 2 LAST CDS_LIB standard
J 2
(3850 3975);
DISPLAY INVISIBLE (3850 3975);
FORCEPROP 1 LAST OFFPAGE TRUE
J 0
(4175 3850);
DISPLAY 0.872340 (4175 3850);
DISPLAY INVISIBLE (4175 3850);
FORCEPROP 1 LAST COMMENT_BODY TRUE
J 0
(3800 3875);
DISPLAY 0.872340 (3800 3875);
PAINT GREEN (3800 3875);
DISPLAY INVISIBLE (3800 3875);
FORCEPROP 2 LAST PATH I168
J 0
(4050 4050);
DISPLAY 1.021277 (4050 4050);
DISPLAY INVISIBLE (4050 4050);
FORCEADD TAP..1
R 2
(-675 400);
FORCEPROP 3 LASTPIN (-625 400) SIG_NAME M_C_CPU1_SB_DQ<0>
J 0
(-615 410);
DISPLAY 0.659574 (-615 410);
PAINT MONO (-615 410);
DISPLAY INVISIBLE (-615 410);
FORCEPROP 1 LASTPIN (-625 400) BN 0
J 2
(-613 408);
DISPLAY 0.680851 (-613 408);
PAINT GREEN (-613 408);
FORCEPROP 2 LAST CDS_LIB standard
J 0
(-675 400);
DISPLAY INVISIBLE (-675 400);
FORCEPROP 1 LAST BODY_TYPE PLUMBING
J 2
(-675 450);
DISPLAY 0.872340 (-675 450);
PAINT GREEN (-675 450);
DISPLAY INVISIBLE (-675 450);
FORCEPROP 1 LAST HDL_TAP TRUE
J 2
(-1000 275);
DISPLAY 0.872340 (-1000 275);
DISPLAY INVISIBLE (-1000 275);
FORCEPROP 1 LAST PATH I17
J 2
(-673 400);
DISPLAY 0.872340 (-673 400);
PAINT GREEN (-673 400);
DISPLAY INVISIBLE (-673 400);
FORCEADD TAP..1
R 2
(-675 350);
FORCEPROP 3 LASTPIN (-625 350) SIG_NAME M_C_CPU1_SB_CB<7>
J 0
(-615 360);
DISPLAY 0.659574 (-615 360);
PAINT MONO (-615 360);
DISPLAY INVISIBLE (-615 360);
FORCEPROP 1 LASTPIN (-625 350) BN 7
J 2
(-613 358);
DISPLAY 0.680851 (-613 358);
PAINT GREEN (-613 358);
FORCEPROP 2 LAST CDS_LIB standard
J 0
(-675 350);
DISPLAY INVISIBLE (-675 350);
FORCEPROP 1 LAST BODY_TYPE PLUMBING
J 2
(-675 400);
DISPLAY 0.872340 (-675 400);
PAINT GREEN (-675 400);
DISPLAY INVISIBLE (-675 400);
FORCEPROP 1 LAST HDL_TAP TRUE
J 2
(-1000 225);
DISPLAY 0.872340 (-1000 225);
DISPLAY INVISIBLE (-1000 225);
FORCEPROP 1 LAST PATH I18
J 2
(-673 350);
DISPLAY 0.872340 (-673 350);
PAINT GREEN (-673 350);
DISPLAY INVISIBLE (-673 350);
FORCEADD TAP..1
R 2
(-675 550);
FORCEPROP 3 LASTPIN (-625 550) SIG_NAME M_C_CPU1_SB_DQ<3>
J 0
(-615 560);
DISPLAY 0.659574 (-615 560);
PAINT MONO (-615 560);
DISPLAY INVISIBLE (-615 560);
FORCEPROP 1 LASTPIN (-625 550) BN 3
J 2
(-613 558);
DISPLAY 0.680851 (-613 558);
PAINT GREEN (-613 558);
FORCEPROP 2 LAST CDS_LIB standard
J 0
(-675 550);
DISPLAY INVISIBLE (-675 550);
FORCEPROP 1 LAST BODY_TYPE PLUMBING
J 2
(-675 600);
DISPLAY 0.872340 (-675 600);
PAINT GREEN (-675 600);
DISPLAY INVISIBLE (-675 600);
FORCEPROP 1 LAST HDL_TAP TRUE
J 2
(-1000 425);
DISPLAY 0.872340 (-1000 425);
DISPLAY INVISIBLE (-1000 425);
FORCEPROP 1 LAST PATH I19
J 2
(-673 550);
DISPLAY 0.872340 (-673 550);
PAINT GREEN (-673 550);
DISPLAY INVISIBLE (-673 550);
FORCEADD OFFPAGE..2
R 2
(-1700 -75);
FORCEPROP 2 LAST $XR1 103 
J 0
(-2075 -75);
DISPLAY 0.638298 (-2075 -75);
PAINT MONO (-2075 -75);
FORCEPROP 2 LAST $XR0 102 
J 0
(-1955 -75);
DISPLAY 0.638298 (-1955 -75);
PAINT MONO (-1955 -75);
FORCEPROP 2 LAST CDS_LIB standard
J 0
(-1700 -75);
PAINT MONO (-1700 -75);
DISPLAY INVISIBLE (-1700 -75);
FORCEPROP 1 LAST OFFPAGE TRUE
J 2
(-2025 -200);
DISPLAY 0.872340 (-2025 -200);
DISPLAY INVISIBLE (-2025 -200);
FORCEPROP 1 LAST COMMENT_BODY TRUE
J 2
(-1655 -170);
DISPLAY 0.872340 (-1655 -170);
PAINT GREEN (-1655 -170);
DISPLAY INVISIBLE (-1655 -170);
FORCEPROP 2 LAST PATH I2
J 0
(-1650 0);
DISPLAY 1.021277 (-1650 0);
DISPLAY INVISIBLE (-1650 0);
FORCEADD TAP..1
R 2
(-675 500);
FORCEPROP 3 LASTPIN (-625 500) SIG_NAME M_C_CPU1_SB_DQ<2>
J 0
(-615 510);
DISPLAY 0.659574 (-615 510);
PAINT MONO (-615 510);
DISPLAY INVISIBLE (-615 510);
FORCEPROP 1 LASTPIN (-625 500) BN 2
J 2
(-613 508);
DISPLAY 0.680851 (-613 508);
PAINT GREEN (-613 508);
FORCEPROP 2 LAST CDS_LIB standard
J 0
(-675 500);
DISPLAY INVISIBLE (-675 500);
FORCEPROP 1 LAST BODY_TYPE PLUMBING
J 2
(-675 550);
DISPLAY 0.872340 (-675 550);
PAINT GREEN (-675 550);
DISPLAY INVISIBLE (-675 550);
FORCEPROP 1 LAST HDL_TAP TRUE
J 2
(-1000 375);
DISPLAY 0.872340 (-1000 375);
DISPLAY INVISIBLE (-1000 375);
FORCEPROP 1 LAST PATH I20
J 2
(-673 500);
DISPLAY 0.872340 (-673 500);
PAINT GREEN (-673 500);
DISPLAY INVISIBLE (-673 500);
FORCEADD TAP..1
R 2
(-675 450);
FORCEPROP 3 LASTPIN (-625 450) SIG_NAME M_C_CPU1_SB_DQ<1>
J 0
(-615 460);
DISPLAY 0.659574 (-615 460);
PAINT MONO (-615 460);
DISPLAY INVISIBLE (-615 460);
FORCEPROP 1 LASTPIN (-625 450) BN 1
J 2
(-613 458);
DISPLAY 0.680851 (-613 458);
PAINT GREEN (-613 458);
FORCEPROP 2 LAST CDS_LIB standard
J 0
(-675 450);
DISPLAY INVISIBLE (-675 450);
FORCEPROP 1 LAST BODY_TYPE PLUMBING
J 2
(-675 500);
DISPLAY 0.872340 (-675 500);
PAINT GREEN (-675 500);
DISPLAY INVISIBLE (-675 500);
FORCEPROP 1 LAST HDL_TAP TRUE
J 2
(-1000 325);
DISPLAY 0.872340 (-1000 325);
DISPLAY INVISIBLE (-1000 325);
FORCEPROP 1 LAST PATH I21
J 2
(-673 450);
DISPLAY 0.872340 (-673 450);
PAINT GREEN (-673 450);
DISPLAY INVISIBLE (-673 450);
FORCEADD TAP..1
R 2
(-675 650);
FORCEPROP 3 LASTPIN (-625 650) SIG_NAME M_C_CPU1_SB_DQ<5>
J 0
(-615 660);
DISPLAY 0.659574 (-615 660);
PAINT MONO (-615 660);
DISPLAY INVISIBLE (-615 660);
FORCEPROP 1 LASTPIN (-625 650) BN 5
J 2
(-613 658);
DISPLAY 0.680851 (-613 658);
PAINT GREEN (-613 658);
FORCEPROP 2 LAST CDS_LIB standard
J 0
(-675 650);
DISPLAY INVISIBLE (-675 650);
FORCEPROP 1 LAST BODY_TYPE PLUMBING
J 2
(-675 700);
DISPLAY 0.872340 (-675 700);
PAINT GREEN (-675 700);
DISPLAY INVISIBLE (-675 700);
FORCEPROP 1 LAST HDL_TAP TRUE
J 2
(-1000 525);
DISPLAY 0.872340 (-1000 525);
DISPLAY INVISIBLE (-1000 525);
FORCEPROP 1 LAST PATH I22
J 2
(-673 650);
DISPLAY 0.872340 (-673 650);
PAINT GREEN (-673 650);
DISPLAY INVISIBLE (-673 650);
FORCEADD TAP..1
R 2
(-675 600);
FORCEPROP 3 LASTPIN (-625 600) SIG_NAME M_C_CPU1_SB_DQ<4>
J 0
(-615 610);
DISPLAY 0.659574 (-615 610);
PAINT MONO (-615 610);
DISPLAY INVISIBLE (-615 610);
FORCEPROP 1 LASTPIN (-625 600) BN 4
J 2
(-613 608);
DISPLAY 0.680851 (-613 608);
PAINT GREEN (-613 608);
FORCEPROP 2 LAST CDS_LIB standard
J 0
(-675 600);
DISPLAY INVISIBLE (-675 600);
FORCEPROP 1 LAST BODY_TYPE PLUMBING
J 2
(-675 650);
DISPLAY 0.872340 (-675 650);
PAINT GREEN (-675 650);
DISPLAY INVISIBLE (-675 650);
FORCEPROP 1 LAST HDL_TAP TRUE
J 2
(-1000 475);
DISPLAY 0.872340 (-1000 475);
DISPLAY INVISIBLE (-1000 475);
FORCEPROP 1 LAST PATH I23
J 2
(-673 600);
DISPLAY 0.872340 (-673 600);
PAINT GREEN (-673 600);
DISPLAY INVISIBLE (-673 600);
FORCEADD TAP..1
R 2
(-675 800);
FORCEPROP 3 LASTPIN (-625 800) SIG_NAME M_C_CPU1_SB_DQ<8>
J 0
(-615 810);
DISPLAY 0.659574 (-615 810);
PAINT MONO (-615 810);
DISPLAY INVISIBLE (-615 810);
FORCEPROP 1 LASTPIN (-625 800) BN 8
J 2
(-613 808);
DISPLAY 0.680851 (-613 808);
PAINT GREEN (-613 808);
FORCEPROP 2 LAST CDS_LIB standard
J 0
(-675 800);
DISPLAY INVISIBLE (-675 800);
FORCEPROP 1 LAST BODY_TYPE PLUMBING
J 2
(-675 850);
DISPLAY 0.872340 (-675 850);
PAINT GREEN (-675 850);
DISPLAY INVISIBLE (-675 850);
FORCEPROP 1 LAST HDL_TAP TRUE
J 2
(-1000 675);
DISPLAY 0.872340 (-1000 675);
DISPLAY INVISIBLE (-1000 675);
FORCEPROP 1 LAST PATH I24
J 2
(-673 800);
DISPLAY 0.872340 (-673 800);
PAINT GREEN (-673 800);
DISPLAY INVISIBLE (-673 800);
FORCEADD TAP..1
R 2
(-675 750);
FORCEPROP 3 LASTPIN (-625 750) SIG_NAME M_C_CPU1_SB_DQ<7>
J 0
(-615 760);
DISPLAY 0.659574 (-615 760);
PAINT MONO (-615 760);
DISPLAY INVISIBLE (-615 760);
FORCEPROP 1 LASTPIN (-625 750) BN 7
J 2
(-613 758);
DISPLAY 0.680851 (-613 758);
PAINT GREEN (-613 758);
FORCEPROP 2 LAST CDS_LIB standard
J 0
(-675 750);
DISPLAY INVISIBLE (-675 750);
FORCEPROP 1 LAST BODY_TYPE PLUMBING
J 2
(-675 800);
DISPLAY 0.872340 (-675 800);
PAINT GREEN (-675 800);
DISPLAY INVISIBLE (-675 800);
FORCEPROP 1 LAST HDL_TAP TRUE
J 2
(-1000 625);
DISPLAY 0.872340 (-1000 625);
DISPLAY INVISIBLE (-1000 625);
FORCEPROP 1 LAST PATH I25
J 2
(-673 750);
DISPLAY 0.872340 (-673 750);
PAINT GREEN (-673 750);
DISPLAY INVISIBLE (-673 750);
FORCEADD TAP..1
R 2
(-675 700);
FORCEPROP 3 LASTPIN (-625 700) SIG_NAME M_C_CPU1_SB_DQ<6>
J 0
(-615 710);
DISPLAY 0.659574 (-615 710);
PAINT MONO (-615 710);
DISPLAY INVISIBLE (-615 710);
FORCEPROP 1 LASTPIN (-625 700) BN 6
J 2
(-613 708);
DISPLAY 0.680851 (-613 708);
PAINT GREEN (-613 708);
FORCEPROP 2 LAST CDS_LIB standard
J 0
(-675 700);
DISPLAY INVISIBLE (-675 700);
FORCEPROP 1 LAST BODY_TYPE PLUMBING
J 2
(-675 750);
DISPLAY 0.872340 (-675 750);
PAINT GREEN (-675 750);
DISPLAY INVISIBLE (-675 750);
FORCEPROP 1 LAST HDL_TAP TRUE
J 2
(-1000 575);
DISPLAY 0.872340 (-1000 575);
DISPLAY INVISIBLE (-1000 575);
FORCEPROP 1 LAST PATH I26
J 2
(-673 700);
DISPLAY 0.872340 (-673 700);
PAINT GREEN (-673 700);
DISPLAY INVISIBLE (-673 700);
FORCEADD TAP..1
R 2
(-675 900);
FORCEPROP 3 LASTPIN (-625 900) SIG_NAME M_C_CPU1_SB_DQ<10>
J 0
(-615 910);
DISPLAY 0.659574 (-615 910);
PAINT MONO (-615 910);
DISPLAY INVISIBLE (-615 910);
FORCEPROP 1 LASTPIN (-625 900) BN 10
J 2
(-613 908);
DISPLAY 0.680851 (-613 908);
PAINT GREEN (-613 908);
FORCEPROP 2 LAST CDS_LIB standard
J 0
(-675 900);
DISPLAY INVISIBLE (-675 900);
FORCEPROP 1 LAST BODY_TYPE PLUMBING
J 2
(-675 950);
DISPLAY 0.872340 (-675 950);
PAINT GREEN (-675 950);
DISPLAY INVISIBLE (-675 950);
FORCEPROP 1 LAST HDL_TAP TRUE
J 2
(-1000 775);
DISPLAY 0.872340 (-1000 775);
DISPLAY INVISIBLE (-1000 775);
FORCEPROP 1 LAST PATH I27
J 2
(-673 900);
DISPLAY 0.872340 (-673 900);
PAINT GREEN (-673 900);
DISPLAY INVISIBLE (-673 900);
FORCEADD TAP..1
R 2
(-675 850);
FORCEPROP 3 LASTPIN (-625 850) SIG_NAME M_C_CPU1_SB_DQ<9>
J 0
(-615 860);
DISPLAY 0.659574 (-615 860);
PAINT MONO (-615 860);
DISPLAY INVISIBLE (-615 860);
FORCEPROP 1 LASTPIN (-625 850) BN 9
J 2
(-613 858);
DISPLAY 0.680851 (-613 858);
PAINT GREEN (-613 858);
FORCEPROP 2 LAST CDS_LIB standard
J 0
(-675 850);
DISPLAY INVISIBLE (-675 850);
FORCEPROP 1 LAST BODY_TYPE PLUMBING
J 2
(-675 900);
DISPLAY 0.872340 (-675 900);
PAINT GREEN (-675 900);
DISPLAY INVISIBLE (-675 900);
FORCEPROP 1 LAST HDL_TAP TRUE
J 2
(-1000 725);
DISPLAY 0.872340 (-1000 725);
DISPLAY INVISIBLE (-1000 725);
FORCEPROP 1 LAST PATH I28
J 2
(-673 850);
DISPLAY 0.872340 (-673 850);
PAINT GREEN (-673 850);
DISPLAY INVISIBLE (-673 850);
FORCEADD TAP..1
R 2
(-675 1050);
FORCEPROP 3 LASTPIN (-625 1050) SIG_NAME M_C_CPU1_SB_DQ<13>
J 0
(-615 1060);
DISPLAY 0.659574 (-615 1060);
PAINT MONO (-615 1060);
DISPLAY INVISIBLE (-615 1060);
FORCEPROP 1 LASTPIN (-625 1050) BN 13
J 2
(-613 1058);
DISPLAY 0.680851 (-613 1058);
PAINT GREEN (-613 1058);
FORCEPROP 2 LAST CDS_LIB standard
J 0
(-675 1050);
DISPLAY INVISIBLE (-675 1050);
FORCEPROP 1 LAST BODY_TYPE PLUMBING
J 2
(-675 1100);
DISPLAY 0.872340 (-675 1100);
PAINT GREEN (-675 1100);
DISPLAY INVISIBLE (-675 1100);
FORCEPROP 1 LAST HDL_TAP TRUE
J 2
(-1000 925);
DISPLAY 0.872340 (-1000 925);
DISPLAY INVISIBLE (-1000 925);
FORCEPROP 1 LAST PATH I29
J 2
(-673 1050);
DISPLAY 0.872340 (-673 1050);
PAINT GREEN (-673 1050);
DISPLAY INVISIBLE (-673 1050);
FORCEADD TAP..1
R 2
(-675 -250);
FORCEPROP 3 LASTPIN (-625 -250) SIG_NAME M_C_CPU1_CLK_DN<0>
J 0
(-615 -240);
DISPLAY 0.659574 (-615 -240);
PAINT MONO (-615 -240);
DISPLAY INVISIBLE (-615 -240);
FORCEPROP 1 LASTPIN (-625 -250) BN 0
J 2
(-613 -242);
DISPLAY 0.680851 (-613 -242);
PAINT GREEN (-613 -242);
FORCEPROP 2 LAST CDS_LIB standard
J 0
(-675 -250);
DISPLAY INVISIBLE (-675 -250);
FORCEPROP 1 LAST BODY_TYPE PLUMBING
J 2
(-675 -200);
DISPLAY 0.872340 (-675 -200);
PAINT GREEN (-675 -200);
DISPLAY INVISIBLE (-675 -200);
FORCEPROP 1 LAST HDL_TAP TRUE
J 2
(-1000 -375);
DISPLAY 0.872340 (-1000 -375);
DISPLAY INVISIBLE (-1000 -375);
FORCEPROP 1 LAST PATH I3
J 2
(-673 -250);
DISPLAY 0.872340 (-673 -250);
PAINT GREEN (-673 -250);
DISPLAY INVISIBLE (-673 -250);
FORCEADD TAP..1
R 2
(-675 1000);
FORCEPROP 3 LASTPIN (-625 1000) SIG_NAME M_C_CPU1_SB_DQ<12>
J 0
(-615 1010);
DISPLAY 0.659574 (-615 1010);
PAINT MONO (-615 1010);
DISPLAY INVISIBLE (-615 1010);
FORCEPROP 1 LASTPIN (-625 1000) BN 12
J 2
(-613 1008);
DISPLAY 0.680851 (-613 1008);
PAINT GREEN (-613 1008);
FORCEPROP 2 LAST CDS_LIB standard
J 0
(-675 1000);
DISPLAY INVISIBLE (-675 1000);
FORCEPROP 1 LAST BODY_TYPE PLUMBING
J 2
(-675 1050);
DISPLAY 0.872340 (-675 1050);
PAINT GREEN (-675 1050);
DISPLAY INVISIBLE (-675 1050);
FORCEPROP 1 LAST HDL_TAP TRUE
J 2
(-1000 875);
DISPLAY 0.872340 (-1000 875);
DISPLAY INVISIBLE (-1000 875);
FORCEPROP 1 LAST PATH I30
J 2
(-673 1000);
DISPLAY 0.872340 (-673 1000);
PAINT GREEN (-673 1000);
DISPLAY INVISIBLE (-673 1000);
FORCEADD TAP..1
R 2
(-675 950);
FORCEPROP 3 LASTPIN (-625 950) SIG_NAME M_C_CPU1_SB_DQ<11>
J 0
(-615 960);
DISPLAY 0.659574 (-615 960);
PAINT MONO (-615 960);
DISPLAY INVISIBLE (-615 960);
FORCEPROP 1 LASTPIN (-625 950) BN 11
J 2
(-613 958);
DISPLAY 0.680851 (-613 958);
PAINT GREEN (-613 958);
FORCEPROP 2 LAST CDS_LIB standard
J 0
(-675 950);
DISPLAY INVISIBLE (-675 950);
FORCEPROP 1 LAST BODY_TYPE PLUMBING
J 2
(-675 1000);
DISPLAY 0.872340 (-675 1000);
PAINT GREEN (-675 1000);
DISPLAY INVISIBLE (-675 1000);
FORCEPROP 1 LAST HDL_TAP TRUE
J 2
(-1000 825);
DISPLAY 0.872340 (-1000 825);
DISPLAY INVISIBLE (-1000 825);
FORCEPROP 1 LAST PATH I31
J 2
(-673 950);
DISPLAY 0.872340 (-673 950);
PAINT GREEN (-673 950);
DISPLAY INVISIBLE (-673 950);
FORCEADD TAP..1
R 2
(-675 1150);
FORCEPROP 3 LASTPIN (-625 1150) SIG_NAME M_C_CPU1_SB_DQ<15>
J 0
(-615 1160);
DISPLAY 0.659574 (-615 1160);
PAINT MONO (-615 1160);
DISPLAY INVISIBLE (-615 1160);
FORCEPROP 1 LASTPIN (-625 1150) BN 15
J 2
(-613 1158);
DISPLAY 0.680851 (-613 1158);
PAINT GREEN (-613 1158);
FORCEPROP 2 LAST CDS_LIB standard
J 0
(-675 1150);
DISPLAY INVISIBLE (-675 1150);
FORCEPROP 1 LAST BODY_TYPE PLUMBING
J 2
(-675 1200);
DISPLAY 0.872340 (-675 1200);
PAINT GREEN (-675 1200);
DISPLAY INVISIBLE (-675 1200);
FORCEPROP 1 LAST HDL_TAP TRUE
J 2
(-1000 1025);
DISPLAY 0.872340 (-1000 1025);
DISPLAY INVISIBLE (-1000 1025);
FORCEPROP 1 LAST PATH I32
J 2
(-673 1150);
DISPLAY 0.872340 (-673 1150);
PAINT GREEN (-673 1150);
DISPLAY INVISIBLE (-673 1150);
FORCEADD TAP..1
R 2
(-675 1100);
FORCEPROP 3 LASTPIN (-625 1100) SIG_NAME M_C_CPU1_SB_DQ<14>
J 0
(-615 1110);
DISPLAY 0.659574 (-615 1110);
PAINT MONO (-615 1110);
DISPLAY INVISIBLE (-615 1110);
FORCEPROP 1 LASTPIN (-625 1100) BN 14
J 2
(-613 1108);
DISPLAY 0.680851 (-613 1108);
PAINT GREEN (-613 1108);
FORCEPROP 2 LAST CDS_LIB standard
J 0
(-675 1100);
DISPLAY INVISIBLE (-675 1100);
FORCEPROP 1 LAST BODY_TYPE PLUMBING
J 2
(-675 1150);
DISPLAY 0.872340 (-675 1150);
PAINT GREEN (-675 1150);
DISPLAY INVISIBLE (-675 1150);
FORCEPROP 1 LAST HDL_TAP TRUE
J 2
(-1000 975);
DISPLAY 0.872340 (-1000 975);
DISPLAY INVISIBLE (-1000 975);
FORCEPROP 1 LAST PATH I33
J 2
(-673 1100);
DISPLAY 0.872340 (-673 1100);
PAINT GREEN (-673 1100);
DISPLAY INVISIBLE (-673 1100);
FORCEADD TAP..1
R 2
(-675 1300);
FORCEPROP 3 LASTPIN (-625 1300) SIG_NAME M_C_CPU1_SB_DQ<18>
J 0
(-615 1310);
DISPLAY 0.659574 (-615 1310);
PAINT MONO (-615 1310);
DISPLAY INVISIBLE (-615 1310);
FORCEPROP 1 LASTPIN (-625 1300) BN 18
J 2
(-613 1308);
DISPLAY 0.680851 (-613 1308);
PAINT GREEN (-613 1308);
FORCEPROP 2 LAST CDS_LIB standard
J 0
(-675 1300);
DISPLAY INVISIBLE (-675 1300);
FORCEPROP 1 LAST BODY_TYPE PLUMBING
J 2
(-675 1350);
DISPLAY 0.872340 (-675 1350);
PAINT GREEN (-675 1350);
DISPLAY INVISIBLE (-675 1350);
FORCEPROP 1 LAST HDL_TAP TRUE
J 2
(-1000 1175);
DISPLAY 0.872340 (-1000 1175);
DISPLAY INVISIBLE (-1000 1175);
FORCEPROP 1 LAST PATH I34
J 2
(-673 1300);
DISPLAY 0.872340 (-673 1300);
PAINT GREEN (-673 1300);
DISPLAY INVISIBLE (-673 1300);
FORCEADD TAP..1
R 2
(-675 1250);
FORCEPROP 3 LASTPIN (-625 1250) SIG_NAME M_C_CPU1_SB_DQ<17>
J 0
(-615 1260);
DISPLAY 0.659574 (-615 1260);
PAINT MONO (-615 1260);
DISPLAY INVISIBLE (-615 1260);
FORCEPROP 1 LASTPIN (-625 1250) BN 17
J 2
(-613 1258);
DISPLAY 0.680851 (-613 1258);
PAINT GREEN (-613 1258);
FORCEPROP 2 LAST CDS_LIB standard
J 0
(-675 1250);
DISPLAY INVISIBLE (-675 1250);
FORCEPROP 1 LAST BODY_TYPE PLUMBING
J 2
(-675 1300);
DISPLAY 0.872340 (-675 1300);
PAINT GREEN (-675 1300);
DISPLAY INVISIBLE (-675 1300);
FORCEPROP 1 LAST HDL_TAP TRUE
J 2
(-1000 1125);
DISPLAY 0.872340 (-1000 1125);
DISPLAY INVISIBLE (-1000 1125);
FORCEPROP 1 LAST PATH I35
J 2
(-673 1250);
DISPLAY 0.872340 (-673 1250);
PAINT GREEN (-673 1250);
DISPLAY INVISIBLE (-673 1250);
FORCEADD TAP..1
R 2
(-675 1200);
FORCEPROP 3 LASTPIN (-625 1200) SIG_NAME M_C_CPU1_SB_DQ<16>
J 0
(-615 1210);
DISPLAY 0.659574 (-615 1210);
PAINT MONO (-615 1210);
DISPLAY INVISIBLE (-615 1210);
FORCEPROP 1 LASTPIN (-625 1200) BN 16
J 2
(-613 1208);
DISPLAY 0.680851 (-613 1208);
PAINT GREEN (-613 1208);
FORCEPROP 2 LAST CDS_LIB standard
J 0
(-675 1200);
DISPLAY INVISIBLE (-675 1200);
FORCEPROP 1 LAST BODY_TYPE PLUMBING
J 2
(-675 1250);
DISPLAY 0.872340 (-675 1250);
PAINT GREEN (-675 1250);
DISPLAY INVISIBLE (-675 1250);
FORCEPROP 1 LAST HDL_TAP TRUE
J 2
(-1000 1075);
DISPLAY 0.872340 (-1000 1075);
DISPLAY INVISIBLE (-1000 1075);
FORCEPROP 1 LAST PATH I36
J 2
(-673 1200);
DISPLAY 0.872340 (-673 1200);
PAINT GREEN (-673 1200);
DISPLAY INVISIBLE (-673 1200);
FORCEADD TAP..1
R 2
(-675 1450);
FORCEPROP 3 LASTPIN (-625 1450) SIG_NAME M_C_CPU1_SB_DQ<21>
J 0
(-615 1460);
DISPLAY 0.659574 (-615 1460);
PAINT MONO (-615 1460);
DISPLAY INVISIBLE (-615 1460);
FORCEPROP 1 LASTPIN (-625 1450) BN 21
J 2
(-613 1458);
DISPLAY 0.680851 (-613 1458);
PAINT GREEN (-613 1458);
FORCEPROP 2 LAST CDS_LIB standard
J 0
(-675 1450);
DISPLAY INVISIBLE (-675 1450);
FORCEPROP 1 LAST BODY_TYPE PLUMBING
J 2
(-675 1500);
DISPLAY 0.872340 (-675 1500);
PAINT GREEN (-675 1500);
DISPLAY INVISIBLE (-675 1500);
FORCEPROP 1 LAST HDL_TAP TRUE
J 2
(-1000 1325);
DISPLAY 0.872340 (-1000 1325);
DISPLAY INVISIBLE (-1000 1325);
FORCEPROP 1 LAST PATH I37
J 2
(-673 1450);
DISPLAY 0.872340 (-673 1450);
PAINT GREEN (-673 1450);
DISPLAY INVISIBLE (-673 1450);
FORCEADD TAP..1
R 2
(-675 1400);
FORCEPROP 3 LASTPIN (-625 1400) SIG_NAME M_C_CPU1_SB_DQ<20>
J 0
(-615 1410);
DISPLAY 0.659574 (-615 1410);
PAINT MONO (-615 1410);
DISPLAY INVISIBLE (-615 1410);
FORCEPROP 1 LASTPIN (-625 1400) BN 20
J 2
(-613 1408);
DISPLAY 0.680851 (-613 1408);
PAINT GREEN (-613 1408);
FORCEPROP 2 LAST CDS_LIB standard
J 0
(-675 1400);
DISPLAY INVISIBLE (-675 1400);
FORCEPROP 1 LAST BODY_TYPE PLUMBING
J 2
(-675 1450);
DISPLAY 0.872340 (-675 1450);
PAINT GREEN (-675 1450);
DISPLAY INVISIBLE (-675 1450);
FORCEPROP 1 LAST HDL_TAP TRUE
J 2
(-1000 1275);
DISPLAY 0.872340 (-1000 1275);
DISPLAY INVISIBLE (-1000 1275);
FORCEPROP 1 LAST PATH I38
J 2
(-673 1400);
DISPLAY 0.872340 (-673 1400);
PAINT GREEN (-673 1400);
DISPLAY INVISIBLE (-673 1400);
FORCEADD TAP..1
R 2
(-675 1350);
FORCEPROP 3 LASTPIN (-625 1350) SIG_NAME M_C_CPU1_SB_DQ<19>
J 0
(-615 1360);
DISPLAY 0.659574 (-615 1360);
PAINT MONO (-615 1360);
DISPLAY INVISIBLE (-615 1360);
FORCEPROP 1 LASTPIN (-625 1350) BN 19
J 2
(-613 1358);
DISPLAY 0.680851 (-613 1358);
PAINT GREEN (-613 1358);
FORCEPROP 2 LAST CDS_LIB standard
J 0
(-675 1350);
DISPLAY INVISIBLE (-675 1350);
FORCEPROP 1 LAST BODY_TYPE PLUMBING
J 2
(-675 1400);
DISPLAY 0.872340 (-675 1400);
PAINT GREEN (-675 1400);
DISPLAY INVISIBLE (-675 1400);
FORCEPROP 1 LAST HDL_TAP TRUE
J 2
(-1000 1225);
DISPLAY 0.872340 (-1000 1225);
DISPLAY INVISIBLE (-1000 1225);
FORCEPROP 1 LAST PATH I39
J 2
(-673 1350);
DISPLAY 0.872340 (-673 1350);
PAINT GREEN (-673 1350);
DISPLAY INVISIBLE (-673 1350);
FORCEADD TAP..1
R 2
(-675 0);
FORCEPROP 3 LASTPIN (-625 0) SIG_NAME M_C_CPU1_SB_CB<0>
J 0
(-615 10);
DISPLAY 0.659574 (-615 10);
PAINT MONO (-615 10);
DISPLAY INVISIBLE (-615 10);
FORCEPROP 1 LASTPIN (-625 0) BN 0
J 2
(-613 8);
DISPLAY 0.680851 (-613 8);
PAINT GREEN (-613 8);
FORCEPROP 2 LAST CDS_LIB standard
J 0
(-675 0);
DISPLAY INVISIBLE (-675 0);
FORCEPROP 1 LAST BODY_TYPE PLUMBING
J 2
(-675 50);
DISPLAY 0.872340 (-675 50);
PAINT GREEN (-675 50);
DISPLAY INVISIBLE (-675 50);
FORCEPROP 1 LAST HDL_TAP TRUE
J 2
(-1000 -125);
DISPLAY 0.872340 (-1000 -125);
DISPLAY INVISIBLE (-1000 -125);
FORCEPROP 1 LAST PATH I4
J 2
(-673 0);
DISPLAY 0.872340 (-673 0);
PAINT GREEN (-673 0);
DISPLAY INVISIBLE (-673 0);
FORCEADD TAP..1
R 2
(-675 1550);
FORCEPROP 3 LASTPIN (-625 1550) SIG_NAME M_C_CPU1_SB_DQ<23>
J 0
(-615 1560);
DISPLAY 0.659574 (-615 1560);
PAINT MONO (-615 1560);
DISPLAY INVISIBLE (-615 1560);
FORCEPROP 1 LASTPIN (-625 1550) BN 23
J 2
(-613 1558);
DISPLAY 0.680851 (-613 1558);
PAINT GREEN (-613 1558);
FORCEPROP 2 LAST CDS_LIB standard
J 0
(-675 1550);
DISPLAY INVISIBLE (-675 1550);
FORCEPROP 1 LAST BODY_TYPE PLUMBING
J 2
(-675 1600);
DISPLAY 0.872340 (-675 1600);
PAINT GREEN (-675 1600);
DISPLAY INVISIBLE (-675 1600);
FORCEPROP 1 LAST HDL_TAP TRUE
J 2
(-1000 1425);
DISPLAY 0.872340 (-1000 1425);
DISPLAY INVISIBLE (-1000 1425);
FORCEPROP 1 LAST PATH I40
J 2
(-673 1550);
DISPLAY 0.872340 (-673 1550);
PAINT GREEN (-673 1550);
DISPLAY INVISIBLE (-673 1550);
FORCEADD TAP..1
R 2
(-675 1500);
FORCEPROP 3 LASTPIN (-625 1500) SIG_NAME M_C_CPU1_SB_DQ<22>
J 0
(-615 1510);
DISPLAY 0.659574 (-615 1510);
PAINT MONO (-615 1510);
DISPLAY INVISIBLE (-615 1510);
FORCEPROP 1 LASTPIN (-625 1500) BN 22
J 2
(-613 1508);
DISPLAY 0.680851 (-613 1508);
PAINT GREEN (-613 1508);
FORCEPROP 2 LAST CDS_LIB standard
J 0
(-675 1500);
DISPLAY INVISIBLE (-675 1500);
FORCEPROP 1 LAST BODY_TYPE PLUMBING
J 2
(-675 1550);
DISPLAY 0.872340 (-675 1550);
PAINT GREEN (-675 1550);
DISPLAY INVISIBLE (-675 1550);
FORCEPROP 1 LAST HDL_TAP TRUE
J 2
(-1000 1375);
DISPLAY 0.872340 (-1000 1375);
DISPLAY INVISIBLE (-1000 1375);
FORCEPROP 1 LAST PATH I41
J 2
(-673 1500);
DISPLAY 0.872340 (-673 1500);
PAINT GREEN (-673 1500);
DISPLAY INVISIBLE (-673 1500);
FORCEADD TAP..1
R 2
(-675 1700);
FORCEPROP 3 LASTPIN (-625 1700) SIG_NAME M_C_CPU1_SB_DQ<26>
J 0
(-615 1710);
DISPLAY 0.659574 (-615 1710);
PAINT MONO (-615 1710);
DISPLAY INVISIBLE (-615 1710);
FORCEPROP 1 LASTPIN (-625 1700) BN 26
J 2
(-613 1708);
DISPLAY 0.680851 (-613 1708);
PAINT GREEN (-613 1708);
FORCEPROP 2 LAST CDS_LIB standard
J 0
(-675 1700);
DISPLAY INVISIBLE (-675 1700);
FORCEPROP 1 LAST BODY_TYPE PLUMBING
J 2
(-675 1750);
DISPLAY 0.872340 (-675 1750);
PAINT GREEN (-675 1750);
DISPLAY INVISIBLE (-675 1750);
FORCEPROP 1 LAST HDL_TAP TRUE
J 2
(-1000 1575);
DISPLAY 0.872340 (-1000 1575);
DISPLAY INVISIBLE (-1000 1575);
FORCEPROP 1 LAST PATH I42
J 2
(-673 1700);
DISPLAY 0.872340 (-673 1700);
PAINT GREEN (-673 1700);
DISPLAY INVISIBLE (-673 1700);
FORCEADD TAP..1
R 2
(-675 1650);
FORCEPROP 3 LASTPIN (-625 1650) SIG_NAME M_C_CPU1_SB_DQ<25>
J 0
(-615 1660);
DISPLAY 0.659574 (-615 1660);
PAINT MONO (-615 1660);
DISPLAY INVISIBLE (-615 1660);
FORCEPROP 1 LASTPIN (-625 1650) BN 25
J 2
(-613 1658);
DISPLAY 0.680851 (-613 1658);
PAINT GREEN (-613 1658);
FORCEPROP 2 LAST CDS_LIB standard
J 0
(-675 1650);
DISPLAY INVISIBLE (-675 1650);
FORCEPROP 1 LAST BODY_TYPE PLUMBING
J 2
(-675 1700);
DISPLAY 0.872340 (-675 1700);
PAINT GREEN (-675 1700);
DISPLAY INVISIBLE (-675 1700);
FORCEPROP 1 LAST HDL_TAP TRUE
J 2
(-1000 1525);
DISPLAY 0.872340 (-1000 1525);
DISPLAY INVISIBLE (-1000 1525);
FORCEPROP 1 LAST PATH I43
J 2
(-673 1650);
DISPLAY 0.872340 (-673 1650);
PAINT GREEN (-673 1650);
DISPLAY INVISIBLE (-673 1650);
FORCEADD TAP..1
R 2
(-675 1600);
FORCEPROP 3 LASTPIN (-625 1600) SIG_NAME M_C_CPU1_SB_DQ<24>
J 0
(-615 1610);
DISPLAY 0.659574 (-615 1610);
PAINT MONO (-615 1610);
DISPLAY INVISIBLE (-615 1610);
FORCEPROP 1 LASTPIN (-625 1600) BN 24
J 2
(-613 1608);
DISPLAY 0.680851 (-613 1608);
PAINT GREEN (-613 1608);
FORCEPROP 2 LAST CDS_LIB standard
J 0
(-675 1600);
DISPLAY INVISIBLE (-675 1600);
FORCEPROP 1 LAST BODY_TYPE PLUMBING
J 2
(-675 1650);
DISPLAY 0.872340 (-675 1650);
PAINT GREEN (-675 1650);
DISPLAY INVISIBLE (-675 1650);
FORCEPROP 1 LAST HDL_TAP TRUE
J 2
(-1000 1475);
DISPLAY 0.872340 (-1000 1475);
DISPLAY INVISIBLE (-1000 1475);
FORCEPROP 1 LAST PATH I44
J 2
(-673 1600);
DISPLAY 0.872340 (-673 1600);
PAINT GREEN (-673 1600);
DISPLAY INVISIBLE (-673 1600);
FORCEADD TAP..1
R 2
(-675 1800);
FORCEPROP 3 LASTPIN (-625 1800) SIG_NAME M_C_CPU1_SB_DQ<28>
J 0
(-615 1810);
DISPLAY 0.659574 (-615 1810);
PAINT MONO (-615 1810);
DISPLAY INVISIBLE (-615 1810);
FORCEPROP 1 LASTPIN (-625 1800) BN 28
J 2
(-613 1808);
DISPLAY 0.680851 (-613 1808);
PAINT GREEN (-613 1808);
FORCEPROP 2 LAST CDS_LIB standard
J 0
(-675 1800);
DISPLAY INVISIBLE (-675 1800);
FORCEPROP 1 LAST BODY_TYPE PLUMBING
J 2
(-675 1850);
DISPLAY 0.872340 (-675 1850);
PAINT GREEN (-675 1850);
DISPLAY INVISIBLE (-675 1850);
FORCEPROP 1 LAST HDL_TAP TRUE
J 2
(-1000 1675);
DISPLAY 0.872340 (-1000 1675);
DISPLAY INVISIBLE (-1000 1675);
FORCEPROP 1 LAST PATH I45
J 2
(-673 1800);
DISPLAY 0.872340 (-673 1800);
PAINT GREEN (-673 1800);
DISPLAY INVISIBLE (-673 1800);
FORCEADD TAP..1
R 2
(-675 1750);
FORCEPROP 3 LASTPIN (-625 1750) SIG_NAME M_C_CPU1_SB_DQ<27>
J 0
(-615 1760);
DISPLAY 0.659574 (-615 1760);
PAINT MONO (-615 1760);
DISPLAY INVISIBLE (-615 1760);
FORCEPROP 1 LASTPIN (-625 1750) BN 27
J 2
(-613 1758);
DISPLAY 0.680851 (-613 1758);
PAINT GREEN (-613 1758);
FORCEPROP 2 LAST CDS_LIB standard
J 0
(-675 1750);
DISPLAY INVISIBLE (-675 1750);
FORCEPROP 1 LAST BODY_TYPE PLUMBING
J 2
(-675 1800);
DISPLAY 0.872340 (-675 1800);
PAINT GREEN (-675 1800);
DISPLAY INVISIBLE (-675 1800);
FORCEPROP 1 LAST HDL_TAP TRUE
J 2
(-1000 1625);
DISPLAY 0.872340 (-1000 1625);
DISPLAY INVISIBLE (-1000 1625);
FORCEPROP 1 LAST PATH I46
J 2
(-673 1750);
DISPLAY 0.872340 (-673 1750);
PAINT GREEN (-673 1750);
DISPLAY INVISIBLE (-673 1750);
FORCEADD TAP..1
R 2
(-675 1900);
FORCEPROP 3 LASTPIN (-625 1900) SIG_NAME M_C_CPU1_SB_DQ<30>
J 0
(-615 1910);
DISPLAY 0.659574 (-615 1910);
PAINT MONO (-615 1910);
DISPLAY INVISIBLE (-615 1910);
FORCEPROP 1 LASTPIN (-625 1900) BN 30
J 2
(-613 1908);
DISPLAY 0.680851 (-613 1908);
PAINT GREEN (-613 1908);
FORCEPROP 2 LAST CDS_LIB standard
J 0
(-675 1900);
DISPLAY INVISIBLE (-675 1900);
FORCEPROP 1 LAST BODY_TYPE PLUMBING
J 2
(-675 1950);
DISPLAY 0.872340 (-675 1950);
PAINT GREEN (-675 1950);
DISPLAY INVISIBLE (-675 1950);
FORCEPROP 1 LAST HDL_TAP TRUE
J 2
(-1000 1775);
DISPLAY 0.872340 (-1000 1775);
DISPLAY INVISIBLE (-1000 1775);
FORCEPROP 1 LAST PATH I47
J 2
(-673 1900);
DISPLAY 0.872340 (-673 1900);
PAINT GREEN (-673 1900);
DISPLAY INVISIBLE (-673 1900);
FORCEADD TAP..1
R 2
(-675 1950);
FORCEPROP 3 LASTPIN (-625 1950) SIG_NAME M_C_CPU1_SB_DQ<31>
J 0
(-615 1960);
DISPLAY 0.659574 (-615 1960);
PAINT MONO (-615 1960);
DISPLAY INVISIBLE (-615 1960);
FORCEPROP 1 LASTPIN (-625 1950) BN 31
J 2
(-613 1958);
DISPLAY 0.680851 (-613 1958);
PAINT GREEN (-613 1958);
FORCEPROP 2 LAST CDS_LIB standard
J 0
(-675 1950);
DISPLAY INVISIBLE (-675 1950);
FORCEPROP 1 LAST BODY_TYPE PLUMBING
J 2
(-675 2000);
DISPLAY 0.872340 (-675 2000);
PAINT GREEN (-675 2000);
DISPLAY INVISIBLE (-675 2000);
FORCEPROP 1 LAST HDL_TAP TRUE
J 2
(-1000 1825);
DISPLAY 0.872340 (-1000 1825);
DISPLAY INVISIBLE (-1000 1825);
FORCEPROP 1 LAST PATH I48
J 2
(-673 1950);
DISPLAY 0.872340 (-673 1950);
PAINT GREEN (-673 1950);
DISPLAY INVISIBLE (-673 1950);
FORCEADD TAP..1
R 2
(-675 1850);
FORCEPROP 3 LASTPIN (-625 1850) SIG_NAME M_C_CPU1_SB_DQ<29>
J 0
(-615 1860);
DISPLAY 0.659574 (-615 1860);
PAINT MONO (-615 1860);
DISPLAY INVISIBLE (-615 1860);
FORCEPROP 1 LASTPIN (-625 1850) BN 29
J 2
(-613 1858);
DISPLAY 0.680851 (-613 1858);
PAINT GREEN (-613 1858);
FORCEPROP 2 LAST CDS_LIB standard
J 0
(-675 1850);
DISPLAY INVISIBLE (-675 1850);
FORCEPROP 1 LAST BODY_TYPE PLUMBING
J 2
(-675 1900);
DISPLAY 0.872340 (-675 1900);
PAINT GREEN (-675 1900);
DISPLAY INVISIBLE (-675 1900);
FORCEPROP 1 LAST HDL_TAP TRUE
J 2
(-1000 1725);
DISPLAY 0.872340 (-1000 1725);
DISPLAY INVISIBLE (-1000 1725);
FORCEPROP 1 LAST PATH I49
J 2
(-673 1850);
DISPLAY 0.872340 (-673 1850);
PAINT GREEN (-673 1850);
DISPLAY INVISIBLE (-673 1850);
FORCEADD TAP..1
R 2
(-675 -200);
FORCEPROP 3 LASTPIN (-625 -200) SIG_NAME M_C_CPU1_CLK_DN<1>
J 0
(-615 -190);
DISPLAY 0.659574 (-615 -190);
PAINT MONO (-615 -190);
DISPLAY INVISIBLE (-615 -190);
FORCEPROP 1 LASTPIN (-625 -200) BN 1
J 2
(-613 -192);
DISPLAY 0.680851 (-613 -192);
PAINT GREEN (-613 -192);
FORCEPROP 2 LAST CDS_LIB standard
J 0
(-675 -200);
DISPLAY INVISIBLE (-675 -200);
FORCEPROP 1 LAST BODY_TYPE PLUMBING
J 2
(-675 -150);
DISPLAY 0.872340 (-675 -150);
PAINT GREEN (-675 -150);
DISPLAY INVISIBLE (-675 -150);
FORCEPROP 1 LAST HDL_TAP TRUE
J 2
(-1000 -325);
DISPLAY 0.872340 (-1000 -325);
DISPLAY INVISIBLE (-1000 -325);
FORCEPROP 1 LAST PATH I5
J 2
(-673 -200);
DISPLAY 0.872340 (-673 -200);
PAINT GREEN (-673 -200);
DISPLAY INVISIBLE (-673 -200);
FORCEADD TAP..1
R 2
(-675 2050);
FORCEPROP 3 LASTPIN (-625 2050) SIG_NAME M_C_CPU1_SA_CB<1>
J 0
(-615 2060);
DISPLAY 0.659574 (-615 2060);
PAINT MONO (-615 2060);
DISPLAY INVISIBLE (-615 2060);
FORCEPROP 1 LASTPIN (-625 2050) BN 1
J 2
(-613 2058);
DISPLAY 0.680851 (-613 2058);
PAINT GREEN (-613 2058);
FORCEPROP 2 LAST CDS_LIB standard
J 0
(-675 2050);
DISPLAY INVISIBLE (-675 2050);
FORCEPROP 1 LAST BODY_TYPE PLUMBING
J 2
(-675 2100);
DISPLAY 0.872340 (-675 2100);
PAINT GREEN (-675 2100);
DISPLAY INVISIBLE (-675 2100);
FORCEPROP 1 LAST HDL_TAP TRUE
J 2
(-1000 1925);
DISPLAY 0.872340 (-1000 1925);
DISPLAY INVISIBLE (-1000 1925);
FORCEPROP 1 LAST PATH I50
J 2
(-673 2050);
DISPLAY 0.872340 (-673 2050);
PAINT GREEN (-673 2050);
DISPLAY INVISIBLE (-673 2050);
FORCEADD TAP..1
R 2
(-675 2000);
FORCEPROP 3 LASTPIN (-625 2000) SIG_NAME M_C_CPU1_SA_CB<0>
J 0
(-615 2010);
DISPLAY 0.659574 (-615 2010);
PAINT MONO (-615 2010);
DISPLAY INVISIBLE (-615 2010);
FORCEPROP 1 LASTPIN (-625 2000) BN 0
J 2
(-613 2008);
DISPLAY 0.680851 (-613 2008);
PAINT GREEN (-613 2008);
FORCEPROP 2 LAST CDS_LIB standard
J 0
(-675 2000);
DISPLAY INVISIBLE (-675 2000);
FORCEPROP 1 LAST BODY_TYPE PLUMBING
J 2
(-675 2050);
DISPLAY 0.872340 (-675 2050);
PAINT GREEN (-675 2050);
DISPLAY INVISIBLE (-675 2050);
FORCEPROP 1 LAST HDL_TAP TRUE
J 2
(-1000 1875);
DISPLAY 0.872340 (-1000 1875);
DISPLAY INVISIBLE (-1000 1875);
FORCEPROP 1 LAST PATH I51
J 2
(-673 2000);
DISPLAY 0.872340 (-673 2000);
PAINT GREEN (-673 2000);
DISPLAY INVISIBLE (-673 2000);
FORCEADD TAP..1
R 2
(-675 2200);
FORCEPROP 3 LASTPIN (-625 2200) SIG_NAME M_C_CPU1_SA_CB<4>
J 0
(-615 2210);
DISPLAY 0.659574 (-615 2210);
PAINT MONO (-615 2210);
DISPLAY INVISIBLE (-615 2210);
FORCEPROP 1 LASTPIN (-625 2200) BN 4
J 2
(-613 2208);
DISPLAY 0.680851 (-613 2208);
PAINT GREEN (-613 2208);
FORCEPROP 2 LAST CDS_LIB standard
J 0
(-675 2200);
DISPLAY INVISIBLE (-675 2200);
FORCEPROP 1 LAST BODY_TYPE PLUMBING
J 2
(-675 2250);
DISPLAY 0.872340 (-675 2250);
PAINT GREEN (-675 2250);
DISPLAY INVISIBLE (-675 2250);
FORCEPROP 1 LAST HDL_TAP TRUE
J 2
(-1000 2075);
DISPLAY 0.872340 (-1000 2075);
DISPLAY INVISIBLE (-1000 2075);
FORCEPROP 1 LAST PATH I52
J 2
(-673 2200);
DISPLAY 0.872340 (-673 2200);
PAINT GREEN (-673 2200);
DISPLAY INVISIBLE (-673 2200);
FORCEADD TAP..1
R 2
(-675 2150);
FORCEPROP 3 LASTPIN (-625 2150) SIG_NAME M_C_CPU1_SA_CB<3>
J 0
(-615 2160);
DISPLAY 0.659574 (-615 2160);
PAINT MONO (-615 2160);
DISPLAY INVISIBLE (-615 2160);
FORCEPROP 1 LASTPIN (-625 2150) BN 3
J 2
(-613 2158);
DISPLAY 0.680851 (-613 2158);
PAINT GREEN (-613 2158);
FORCEPROP 2 LAST CDS_LIB standard
J 0
(-675 2150);
DISPLAY INVISIBLE (-675 2150);
FORCEPROP 1 LAST BODY_TYPE PLUMBING
J 2
(-675 2200);
DISPLAY 0.872340 (-675 2200);
PAINT GREEN (-675 2200);
DISPLAY INVISIBLE (-675 2200);
FORCEPROP 1 LAST HDL_TAP TRUE
J 2
(-1000 2025);
DISPLAY 0.872340 (-1000 2025);
DISPLAY INVISIBLE (-1000 2025);
FORCEPROP 1 LAST PATH I53
J 2
(-673 2150);
DISPLAY 0.872340 (-673 2150);
PAINT GREEN (-673 2150);
DISPLAY INVISIBLE (-673 2150);
FORCEADD TAP..1
R 2
(-675 2100);
FORCEPROP 3 LASTPIN (-625 2100) SIG_NAME M_C_CPU1_SA_CB<2>
J 0
(-615 2110);
DISPLAY 0.659574 (-615 2110);
PAINT MONO (-615 2110);
DISPLAY INVISIBLE (-615 2110);
FORCEPROP 1 LASTPIN (-625 2100) BN 2
J 2
(-613 2108);
DISPLAY 0.680851 (-613 2108);
PAINT GREEN (-613 2108);
FORCEPROP 2 LAST CDS_LIB standard
J 0
(-675 2100);
DISPLAY INVISIBLE (-675 2100);
FORCEPROP 1 LAST BODY_TYPE PLUMBING
J 2
(-675 2150);
DISPLAY 0.872340 (-675 2150);
PAINT GREEN (-675 2150);
DISPLAY INVISIBLE (-675 2150);
FORCEPROP 1 LAST HDL_TAP TRUE
J 2
(-1000 1975);
DISPLAY 0.872340 (-1000 1975);
DISPLAY INVISIBLE (-1000 1975);
FORCEPROP 1 LAST PATH I54
J 2
(-673 2100);
DISPLAY 0.872340 (-673 2100);
PAINT GREEN (-673 2100);
DISPLAY INVISIBLE (-673 2100);
FORCEADD TAP..1
R 2
(-675 2300);
FORCEPROP 3 LASTPIN (-625 2300) SIG_NAME M_C_CPU1_SA_CB<6>
J 0
(-615 2310);
DISPLAY 0.659574 (-615 2310);
PAINT MONO (-615 2310);
DISPLAY INVISIBLE (-615 2310);
FORCEPROP 1 LASTPIN (-625 2300) BN 6
J 2
(-613 2308);
DISPLAY 0.680851 (-613 2308);
PAINT GREEN (-613 2308);
FORCEPROP 2 LAST CDS_LIB standard
J 0
(-675 2300);
DISPLAY INVISIBLE (-675 2300);
FORCEPROP 1 LAST BODY_TYPE PLUMBING
J 2
(-675 2350);
DISPLAY 0.872340 (-675 2350);
PAINT GREEN (-675 2350);
DISPLAY INVISIBLE (-675 2350);
FORCEPROP 1 LAST HDL_TAP TRUE
J 2
(-1000 2175);
DISPLAY 0.872340 (-1000 2175);
DISPLAY INVISIBLE (-1000 2175);
FORCEPROP 1 LAST PATH I55
J 2
(-673 2300);
DISPLAY 0.872340 (-673 2300);
PAINT GREEN (-673 2300);
DISPLAY INVISIBLE (-673 2300);
FORCEADD TAP..1
R 2
(-675 2250);
FORCEPROP 3 LASTPIN (-625 2250) SIG_NAME M_C_CPU1_SA_CB<5>
J 0
(-615 2260);
DISPLAY 0.659574 (-615 2260);
PAINT MONO (-615 2260);
DISPLAY INVISIBLE (-615 2260);
FORCEPROP 1 LASTPIN (-625 2250) BN 5
J 2
(-613 2258);
DISPLAY 0.680851 (-613 2258);
PAINT GREEN (-613 2258);
FORCEPROP 2 LAST CDS_LIB standard
J 0
(-675 2250);
DISPLAY INVISIBLE (-675 2250);
FORCEPROP 1 LAST BODY_TYPE PLUMBING
J 2
(-675 2300);
DISPLAY 0.872340 (-675 2300);
PAINT GREEN (-675 2300);
DISPLAY INVISIBLE (-675 2300);
FORCEPROP 1 LAST HDL_TAP TRUE
J 2
(-1000 2125);
DISPLAY 0.872340 (-1000 2125);
DISPLAY INVISIBLE (-1000 2125);
FORCEPROP 1 LAST PATH I56
J 2
(-673 2250);
DISPLAY 0.872340 (-673 2250);
PAINT GREEN (-673 2250);
DISPLAY INVISIBLE (-673 2250);
FORCEADD OFFPAGE..3
R 2
(-1700 3975);
FORCEPROP 2 LAST $XR1 103 
J 0
(-2130 3975);
DISPLAY 0.638298 (-2130 3975);
PAINT MONO (-2130 3975);
FORCEPROP 2 LAST $XR0 102 
J 0
(-2010 3975);
DISPLAY 0.638298 (-2010 3975);
PAINT MONO (-2010 3975);
FORCEPROP 2 LAST CDS_LIB standard
J 0
(-1700 3975);
DISPLAY INVISIBLE (-1700 3975);
FORCEPROP 1 LAST OFFPAGE TRUE
J 2
(-2025 3850);
DISPLAY 0.872340 (-2025 3850);
DISPLAY INVISIBLE (-2025 3850);
FORCEPROP 1 LAST COMMENT_BODY TRUE
J 2
(-1650 3875);
DISPLAY 0.872340 (-1650 3875);
PAINT GREEN (-1650 3875);
DISPLAY INVISIBLE (-1650 3875);
FORCEPROP 2 LAST PATH I57
J 0
(-1650 4050);
DISPLAY 1.021277 (-1650 4050);
DISPLAY INVISIBLE (-1650 4050);
FORCEADD TAP..1
R 2
(-675 2450);
FORCEPROP 3 LASTPIN (-625 2450) SIG_NAME M_C_CPU1_SA_DQ<1>
J 0
(-615 2460);
DISPLAY 0.659574 (-615 2460);
PAINT MONO (-615 2460);
DISPLAY INVISIBLE (-615 2460);
FORCEPROP 1 LASTPIN (-625 2450) BN 1
J 2
(-613 2458);
DISPLAY 0.680851 (-613 2458);
PAINT GREEN (-613 2458);
FORCEPROP 2 LAST CDS_LIB standard
J 0
(-675 2450);
DISPLAY INVISIBLE (-675 2450);
FORCEPROP 1 LAST BODY_TYPE PLUMBING
J 2
(-675 2500);
DISPLAY 0.872340 (-675 2500);
PAINT GREEN (-675 2500);
DISPLAY INVISIBLE (-675 2500);
FORCEPROP 1 LAST HDL_TAP TRUE
J 2
(-1000 2325);
DISPLAY 0.872340 (-1000 2325);
DISPLAY INVISIBLE (-1000 2325);
FORCEPROP 1 LAST PATH I58
J 2
(-673 2450);
DISPLAY 0.872340 (-673 2450);
PAINT GREEN (-673 2450);
DISPLAY INVISIBLE (-673 2450);
FORCEADD TAP..1
R 2
(-675 2400);
FORCEPROP 3 LASTPIN (-625 2400) SIG_NAME M_C_CPU1_SA_DQ<0>
J 0
(-615 2410);
DISPLAY 0.659574 (-615 2410);
PAINT MONO (-615 2410);
DISPLAY INVISIBLE (-615 2410);
FORCEPROP 1 LASTPIN (-625 2400) BN 0
J 2
(-613 2408);
DISPLAY 0.680851 (-613 2408);
PAINT GREEN (-613 2408);
FORCEPROP 2 LAST CDS_LIB standard
J 0
(-675 2400);
DISPLAY INVISIBLE (-675 2400);
FORCEPROP 1 LAST BODY_TYPE PLUMBING
J 2
(-675 2450);
DISPLAY 0.872340 (-675 2450);
PAINT GREEN (-675 2450);
DISPLAY INVISIBLE (-675 2450);
FORCEPROP 1 LAST HDL_TAP TRUE
J 2
(-1000 2275);
DISPLAY 0.872340 (-1000 2275);
DISPLAY INVISIBLE (-1000 2275);
FORCEPROP 1 LAST PATH I59
J 2
(-673 2400);
DISPLAY 0.872340 (-673 2400);
PAINT GREEN (-673 2400);
DISPLAY INVISIBLE (-673 2400);
FORCEADD TAP..1
R 2
(-675 -100);
FORCEPROP 3 LASTPIN (-625 -100) SIG_NAME M_C_CPU1_CLK_DP<1>
J 0
(-615 -90);
DISPLAY 0.659574 (-615 -90);
PAINT MONO (-615 -90);
DISPLAY INVISIBLE (-615 -90);
FORCEPROP 1 LASTPIN (-625 -100) BN 1
J 2
(-613 -92);
DISPLAY 0.680851 (-613 -92);
PAINT GREEN (-613 -92);
FORCEPROP 2 LAST CDS_LIB standard
J 0
(-675 -100);
DISPLAY INVISIBLE (-675 -100);
FORCEPROP 1 LAST BODY_TYPE PLUMBING
J 2
(-675 -50);
DISPLAY 0.872340 (-675 -50);
PAINT GREEN (-675 -50);
DISPLAY INVISIBLE (-675 -50);
FORCEPROP 1 LAST HDL_TAP TRUE
J 2
(-1000 -225);
DISPLAY 0.872340 (-1000 -225);
DISPLAY INVISIBLE (-1000 -225);
FORCEPROP 1 LAST PATH I6
J 2
(-673 -100);
DISPLAY 0.872340 (-673 -100);
PAINT GREEN (-673 -100);
DISPLAY INVISIBLE (-673 -100);
FORCEADD TAP..1
R 2
(-675 2350);
FORCEPROP 3 LASTPIN (-625 2350) SIG_NAME M_C_CPU1_SA_CB<7>
J 0
(-615 2360);
DISPLAY 0.659574 (-615 2360);
PAINT MONO (-615 2360);
DISPLAY INVISIBLE (-615 2360);
FORCEPROP 1 LASTPIN (-625 2350) BN 7
J 2
(-613 2358);
DISPLAY 0.680851 (-613 2358);
PAINT GREEN (-613 2358);
FORCEPROP 2 LAST CDS_LIB standard
J 0
(-675 2350);
DISPLAY INVISIBLE (-675 2350);
FORCEPROP 1 LAST BODY_TYPE PLUMBING
J 2
(-675 2400);
DISPLAY 0.872340 (-675 2400);
PAINT GREEN (-675 2400);
DISPLAY INVISIBLE (-675 2400);
FORCEPROP 1 LAST HDL_TAP TRUE
J 2
(-1000 2225);
DISPLAY 0.872340 (-1000 2225);
DISPLAY INVISIBLE (-1000 2225);
FORCEPROP 1 LAST PATH I60
J 2
(-673 2350);
DISPLAY 0.872340 (-673 2350);
PAINT GREEN (-673 2350);
DISPLAY INVISIBLE (-673 2350);
FORCEADD TAP..1
R 2
(-675 2600);
FORCEPROP 3 LASTPIN (-625 2600) SIG_NAME M_C_CPU1_SA_DQ<4>
J 0
(-615 2610);
DISPLAY 0.659574 (-615 2610);
PAINT MONO (-615 2610);
DISPLAY INVISIBLE (-615 2610);
FORCEPROP 1 LASTPIN (-625 2600) BN 4
J 2
(-613 2608);
DISPLAY 0.680851 (-613 2608);
PAINT GREEN (-613 2608);
FORCEPROP 2 LAST CDS_LIB standard
J 0
(-675 2600);
DISPLAY INVISIBLE (-675 2600);
FORCEPROP 1 LAST BODY_TYPE PLUMBING
J 2
(-675 2650);
DISPLAY 0.872340 (-675 2650);
PAINT GREEN (-675 2650);
DISPLAY INVISIBLE (-675 2650);
FORCEPROP 1 LAST HDL_TAP TRUE
J 2
(-1000 2475);
DISPLAY 0.872340 (-1000 2475);
DISPLAY INVISIBLE (-1000 2475);
FORCEPROP 1 LAST PATH I61
J 2
(-673 2600);
DISPLAY 0.872340 (-673 2600);
PAINT GREEN (-673 2600);
DISPLAY INVISIBLE (-673 2600);
FORCEADD TAP..1
R 2
(-675 2550);
FORCEPROP 3 LASTPIN (-625 2550) SIG_NAME M_C_CPU1_SA_DQ<3>
J 0
(-615 2560);
DISPLAY 0.659574 (-615 2560);
PAINT MONO (-615 2560);
DISPLAY INVISIBLE (-615 2560);
FORCEPROP 1 LASTPIN (-625 2550) BN 3
J 2
(-613 2558);
DISPLAY 0.680851 (-613 2558);
PAINT GREEN (-613 2558);
FORCEPROP 2 LAST CDS_LIB standard
J 0
(-675 2550);
DISPLAY INVISIBLE (-675 2550);
FORCEPROP 1 LAST BODY_TYPE PLUMBING
J 2
(-675 2600);
DISPLAY 0.872340 (-675 2600);
PAINT GREEN (-675 2600);
DISPLAY INVISIBLE (-675 2600);
FORCEPROP 1 LAST HDL_TAP TRUE
J 2
(-1000 2425);
DISPLAY 0.872340 (-1000 2425);
DISPLAY INVISIBLE (-1000 2425);
FORCEPROP 1 LAST PATH I62
J 2
(-673 2550);
DISPLAY 0.872340 (-673 2550);
PAINT GREEN (-673 2550);
DISPLAY INVISIBLE (-673 2550);
FORCEADD TAP..1
R 2
(-675 2500);
FORCEPROP 3 LASTPIN (-625 2500) SIG_NAME M_C_CPU1_SA_DQ<2>
J 0
(-615 2510);
DISPLAY 0.659574 (-615 2510);
PAINT MONO (-615 2510);
DISPLAY INVISIBLE (-615 2510);
FORCEPROP 1 LASTPIN (-625 2500) BN 2
J 2
(-613 2508);
DISPLAY 0.680851 (-613 2508);
PAINT GREEN (-613 2508);
FORCEPROP 2 LAST CDS_LIB standard
J 0
(-675 2500);
DISPLAY INVISIBLE (-675 2500);
FORCEPROP 1 LAST BODY_TYPE PLUMBING
J 2
(-675 2550);
DISPLAY 0.872340 (-675 2550);
PAINT GREEN (-675 2550);
DISPLAY INVISIBLE (-675 2550);
FORCEPROP 1 LAST HDL_TAP TRUE
J 2
(-1000 2375);
DISPLAY 0.872340 (-1000 2375);
DISPLAY INVISIBLE (-1000 2375);
FORCEPROP 1 LAST PATH I63
J 2
(-673 2500);
DISPLAY 0.872340 (-673 2500);
PAINT GREEN (-673 2500);
DISPLAY INVISIBLE (-673 2500);
FORCEADD TAP..1
R 2
(-675 2700);
FORCEPROP 3 LASTPIN (-625 2700) SIG_NAME M_C_CPU1_SA_DQ<6>
J 0
(-615 2710);
DISPLAY 0.659574 (-615 2710);
PAINT MONO (-615 2710);
DISPLAY INVISIBLE (-615 2710);
FORCEPROP 1 LASTPIN (-625 2700) BN 6
J 2
(-613 2708);
DISPLAY 0.680851 (-613 2708);
PAINT GREEN (-613 2708);
FORCEPROP 2 LAST CDS_LIB standard
J 0
(-675 2700);
DISPLAY INVISIBLE (-675 2700);
FORCEPROP 1 LAST BODY_TYPE PLUMBING
J 2
(-675 2750);
DISPLAY 0.872340 (-675 2750);
PAINT GREEN (-675 2750);
DISPLAY INVISIBLE (-675 2750);
FORCEPROP 1 LAST HDL_TAP TRUE
J 2
(-1000 2575);
DISPLAY 0.872340 (-1000 2575);
DISPLAY INVISIBLE (-1000 2575);
FORCEPROP 1 LAST PATH I64
J 2
(-673 2700);
DISPLAY 0.872340 (-673 2700);
PAINT GREEN (-673 2700);
DISPLAY INVISIBLE (-673 2700);
FORCEADD TAP..1
R 2
(-675 2650);
FORCEPROP 3 LASTPIN (-625 2650) SIG_NAME M_C_CPU1_SA_DQ<5>
J 0
(-615 2660);
DISPLAY 0.659574 (-615 2660);
PAINT MONO (-615 2660);
DISPLAY INVISIBLE (-615 2660);
FORCEPROP 1 LASTPIN (-625 2650) BN 5
J 2
(-613 2658);
DISPLAY 0.680851 (-613 2658);
PAINT GREEN (-613 2658);
FORCEPROP 2 LAST CDS_LIB standard
J 0
(-675 2650);
DISPLAY INVISIBLE (-675 2650);
FORCEPROP 1 LAST BODY_TYPE PLUMBING
J 2
(-675 2700);
DISPLAY 0.872340 (-675 2700);
PAINT GREEN (-675 2700);
DISPLAY INVISIBLE (-675 2700);
FORCEPROP 1 LAST HDL_TAP TRUE
J 2
(-1000 2525);
DISPLAY 0.872340 (-1000 2525);
DISPLAY INVISIBLE (-1000 2525);
FORCEPROP 1 LAST PATH I65
J 2
(-673 2650);
DISPLAY 0.872340 (-673 2650);
PAINT GREEN (-673 2650);
DISPLAY INVISIBLE (-673 2650);
FORCEADD TAP..1
R 2
(-675 2850);
FORCEPROP 3 LASTPIN (-625 2850) SIG_NAME M_C_CPU1_SA_DQ<9>
J 0
(-615 2860);
DISPLAY 0.659574 (-615 2860);
PAINT MONO (-615 2860);
DISPLAY INVISIBLE (-615 2860);
FORCEPROP 1 LASTPIN (-625 2850) BN 9
J 2
(-613 2858);
DISPLAY 0.680851 (-613 2858);
PAINT GREEN (-613 2858);
FORCEPROP 2 LAST CDS_LIB standard
J 0
(-675 2850);
DISPLAY INVISIBLE (-675 2850);
FORCEPROP 1 LAST BODY_TYPE PLUMBING
J 2
(-675 2900);
DISPLAY 0.872340 (-675 2900);
PAINT GREEN (-675 2900);
DISPLAY INVISIBLE (-675 2900);
FORCEPROP 1 LAST HDL_TAP TRUE
J 2
(-1000 2725);
DISPLAY 0.872340 (-1000 2725);
DISPLAY INVISIBLE (-1000 2725);
FORCEPROP 1 LAST PATH I66
J 2
(-673 2850);
DISPLAY 0.872340 (-673 2850);
PAINT GREEN (-673 2850);
DISPLAY INVISIBLE (-673 2850);
FORCEADD TAP..1
R 2
(-675 2800);
FORCEPROP 3 LASTPIN (-625 2800) SIG_NAME M_C_CPU1_SA_DQ<8>
J 0
(-615 2810);
DISPLAY 0.659574 (-615 2810);
PAINT MONO (-615 2810);
DISPLAY INVISIBLE (-615 2810);
FORCEPROP 1 LASTPIN (-625 2800) BN 8
J 2
(-613 2808);
DISPLAY 0.680851 (-613 2808);
PAINT GREEN (-613 2808);
FORCEPROP 2 LAST CDS_LIB standard
J 0
(-675 2800);
DISPLAY INVISIBLE (-675 2800);
FORCEPROP 1 LAST BODY_TYPE PLUMBING
J 2
(-675 2850);
DISPLAY 0.872340 (-675 2850);
PAINT GREEN (-675 2850);
DISPLAY INVISIBLE (-675 2850);
FORCEPROP 1 LAST HDL_TAP TRUE
J 2
(-1000 2675);
DISPLAY 0.872340 (-1000 2675);
DISPLAY INVISIBLE (-1000 2675);
FORCEPROP 1 LAST PATH I67
J 2
(-673 2800);
DISPLAY 0.872340 (-673 2800);
PAINT GREEN (-673 2800);
DISPLAY INVISIBLE (-673 2800);
FORCEADD TAP..1
R 2
(-675 2750);
FORCEPROP 3 LASTPIN (-625 2750) SIG_NAME M_C_CPU1_SA_DQ<7>
J 0
(-615 2760);
DISPLAY 0.659574 (-615 2760);
PAINT MONO (-615 2760);
DISPLAY INVISIBLE (-615 2760);
FORCEPROP 1 LASTPIN (-625 2750) BN 7
J 2
(-613 2758);
DISPLAY 0.680851 (-613 2758);
PAINT GREEN (-613 2758);
FORCEPROP 2 LAST CDS_LIB standard
J 0
(-675 2750);
DISPLAY INVISIBLE (-675 2750);
FORCEPROP 1 LAST BODY_TYPE PLUMBING
J 2
(-675 2800);
DISPLAY 0.872340 (-675 2800);
PAINT GREEN (-675 2800);
DISPLAY INVISIBLE (-675 2800);
FORCEPROP 1 LAST HDL_TAP TRUE
J 2
(-1000 2625);
DISPLAY 0.872340 (-1000 2625);
DISPLAY INVISIBLE (-1000 2625);
FORCEPROP 1 LAST PATH I68
J 2
(-673 2750);
DISPLAY 0.872340 (-673 2750);
PAINT GREEN (-673 2750);
DISPLAY INVISIBLE (-673 2750);
FORCEADD TAP..1
R 2
(-675 2950);
FORCEPROP 3 LASTPIN (-625 2950) SIG_NAME M_C_CPU1_SA_DQ<11>
J 0
(-615 2960);
DISPLAY 0.659574 (-615 2960);
PAINT MONO (-615 2960);
DISPLAY INVISIBLE (-615 2960);
FORCEPROP 1 LASTPIN (-625 2950) BN 11
J 2
(-613 2958);
DISPLAY 0.680851 (-613 2958);
PAINT GREEN (-613 2958);
FORCEPROP 2 LAST CDS_LIB standard
J 0
(-675 2950);
DISPLAY INVISIBLE (-675 2950);
FORCEPROP 1 LAST BODY_TYPE PLUMBING
J 2
(-675 3000);
DISPLAY 0.872340 (-675 3000);
PAINT GREEN (-675 3000);
DISPLAY INVISIBLE (-675 3000);
FORCEPROP 1 LAST HDL_TAP TRUE
J 2
(-1000 2825);
DISPLAY 0.872340 (-1000 2825);
DISPLAY INVISIBLE (-1000 2825);
FORCEPROP 1 LAST PATH I69
J 2
(-673 2950);
DISPLAY 0.872340 (-673 2950);
PAINT GREEN (-673 2950);
DISPLAY INVISIBLE (-673 2950);
FORCEADD TAP..1
R 2
(-675 -150);
FORCEPROP 3 LASTPIN (-625 -150) SIG_NAME M_C_CPU1_CLK_DP<0>
J 0
(-615 -140);
DISPLAY 0.659574 (-615 -140);
PAINT MONO (-615 -140);
DISPLAY INVISIBLE (-615 -140);
FORCEPROP 1 LASTPIN (-625 -150) BN 0
J 2
(-613 -142);
DISPLAY 0.680851 (-613 -142);
PAINT GREEN (-613 -142);
FORCEPROP 2 LAST CDS_LIB standard
J 0
(-675 -150);
DISPLAY INVISIBLE (-675 -150);
FORCEPROP 1 LAST BODY_TYPE PLUMBING
J 2
(-675 -100);
DISPLAY 0.872340 (-675 -100);
PAINT GREEN (-675 -100);
DISPLAY INVISIBLE (-675 -100);
FORCEPROP 1 LAST HDL_TAP TRUE
J 2
(-1000 -275);
DISPLAY 0.872340 (-1000 -275);
DISPLAY INVISIBLE (-1000 -275);
FORCEPROP 1 LAST PATH I7
J 2
(-673 -150);
DISPLAY 0.872340 (-673 -150);
PAINT GREEN (-673 -150);
DISPLAY INVISIBLE (-673 -150);
FORCEADD TAP..1
R 2
(-675 2900);
FORCEPROP 3 LASTPIN (-625 2900) SIG_NAME M_C_CPU1_SA_DQ<10>
J 0
(-615 2910);
DISPLAY 0.659574 (-615 2910);
PAINT MONO (-615 2910);
DISPLAY INVISIBLE (-615 2910);
FORCEPROP 1 LASTPIN (-625 2900) BN 10
J 2
(-613 2908);
DISPLAY 0.680851 (-613 2908);
PAINT GREEN (-613 2908);
FORCEPROP 2 LAST CDS_LIB standard
J 0
(-675 2900);
DISPLAY INVISIBLE (-675 2900);
FORCEPROP 1 LAST BODY_TYPE PLUMBING
J 2
(-675 2950);
DISPLAY 0.872340 (-675 2950);
PAINT GREEN (-675 2950);
DISPLAY INVISIBLE (-675 2950);
FORCEPROP 1 LAST HDL_TAP TRUE
J 2
(-1000 2775);
DISPLAY 0.872340 (-1000 2775);
DISPLAY INVISIBLE (-1000 2775);
FORCEPROP 1 LAST PATH I70
J 2
(-673 2900);
DISPLAY 0.872340 (-673 2900);
PAINT GREEN (-673 2900);
DISPLAY INVISIBLE (-673 2900);
FORCEADD TAP..1
R 2
(-675 3100);
FORCEPROP 3 LASTPIN (-625 3100) SIG_NAME M_C_CPU1_SA_DQ<14>
J 0
(-615 3110);
DISPLAY 0.659574 (-615 3110);
PAINT MONO (-615 3110);
DISPLAY INVISIBLE (-615 3110);
FORCEPROP 1 LASTPIN (-625 3100) BN 14
J 2
(-613 3108);
DISPLAY 0.680851 (-613 3108);
PAINT GREEN (-613 3108);
FORCEPROP 2 LAST CDS_LIB standard
J 0
(-675 3100);
DISPLAY INVISIBLE (-675 3100);
FORCEPROP 1 LAST BODY_TYPE PLUMBING
J 2
(-675 3150);
DISPLAY 0.872340 (-675 3150);
PAINT GREEN (-675 3150);
DISPLAY INVISIBLE (-675 3150);
FORCEPROP 1 LAST HDL_TAP TRUE
J 2
(-1000 2975);
DISPLAY 0.872340 (-1000 2975);
DISPLAY INVISIBLE (-1000 2975);
FORCEPROP 1 LAST PATH I71
J 2
(-673 3100);
DISPLAY 0.872340 (-673 3100);
PAINT GREEN (-673 3100);
DISPLAY INVISIBLE (-673 3100);
FORCEADD TAP..1
R 2
(-675 3050);
FORCEPROP 3 LASTPIN (-625 3050) SIG_NAME M_C_CPU1_SA_DQ<13>
J 0
(-615 3060);
DISPLAY 0.659574 (-615 3060);
PAINT MONO (-615 3060);
DISPLAY INVISIBLE (-615 3060);
FORCEPROP 1 LASTPIN (-625 3050) BN 13
J 2
(-613 3058);
DISPLAY 0.680851 (-613 3058);
PAINT GREEN (-613 3058);
FORCEPROP 2 LAST CDS_LIB standard
J 0
(-675 3050);
DISPLAY INVISIBLE (-675 3050);
FORCEPROP 1 LAST BODY_TYPE PLUMBING
J 2
(-675 3100);
DISPLAY 0.872340 (-675 3100);
PAINT GREEN (-675 3100);
DISPLAY INVISIBLE (-675 3100);
FORCEPROP 1 LAST HDL_TAP TRUE
J 2
(-1000 2925);
DISPLAY 0.872340 (-1000 2925);
DISPLAY INVISIBLE (-1000 2925);
FORCEPROP 1 LAST PATH I72
J 2
(-673 3050);
DISPLAY 0.872340 (-673 3050);
PAINT GREEN (-673 3050);
DISPLAY INVISIBLE (-673 3050);
FORCEADD TAP..1
R 2
(-675 3000);
FORCEPROP 3 LASTPIN (-625 3000) SIG_NAME M_C_CPU1_SA_DQ<12>
J 0
(-615 3010);
DISPLAY 0.659574 (-615 3010);
PAINT MONO (-615 3010);
DISPLAY INVISIBLE (-615 3010);
FORCEPROP 1 LASTPIN (-625 3000) BN 12
J 2
(-613 3008);
DISPLAY 0.680851 (-613 3008);
PAINT GREEN (-613 3008);
FORCEPROP 2 LAST CDS_LIB standard
J 0
(-675 3000);
DISPLAY INVISIBLE (-675 3000);
FORCEPROP 1 LAST BODY_TYPE PLUMBING
J 2
(-675 3050);
DISPLAY 0.872340 (-675 3050);
PAINT GREEN (-675 3050);
DISPLAY INVISIBLE (-675 3050);
FORCEPROP 1 LAST HDL_TAP TRUE
J 2
(-1000 2875);
DISPLAY 0.872340 (-1000 2875);
DISPLAY INVISIBLE (-1000 2875);
FORCEPROP 1 LAST PATH I73
J 2
(-673 3000);
DISPLAY 0.872340 (-673 3000);
PAINT GREEN (-673 3000);
DISPLAY INVISIBLE (-673 3000);
FORCEADD TAP..1
R 2
(-675 3200);
FORCEPROP 3 LASTPIN (-625 3200) SIG_NAME M_C_CPU1_SA_DQ<16>
J 0
(-615 3210);
DISPLAY 0.659574 (-615 3210);
PAINT MONO (-615 3210);
DISPLAY INVISIBLE (-615 3210);
FORCEPROP 1 LASTPIN (-625 3200) BN 16
J 2
(-613 3208);
DISPLAY 0.680851 (-613 3208);
PAINT GREEN (-613 3208);
FORCEPROP 2 LAST CDS_LIB standard
J 0
(-675 3200);
DISPLAY INVISIBLE (-675 3200);
FORCEPROP 1 LAST BODY_TYPE PLUMBING
J 2
(-675 3250);
DISPLAY 0.872340 (-675 3250);
PAINT GREEN (-675 3250);
DISPLAY INVISIBLE (-675 3250);
FORCEPROP 1 LAST HDL_TAP TRUE
J 2
(-1000 3075);
DISPLAY 0.872340 (-1000 3075);
DISPLAY INVISIBLE (-1000 3075);
FORCEPROP 1 LAST PATH I74
J 2
(-673 3200);
DISPLAY 0.872340 (-673 3200);
PAINT GREEN (-673 3200);
DISPLAY INVISIBLE (-673 3200);
FORCEADD TAP..1
R 2
(-675 3150);
FORCEPROP 3 LASTPIN (-625 3150) SIG_NAME M_C_CPU1_SA_DQ<15>
J 0
(-615 3160);
DISPLAY 0.659574 (-615 3160);
PAINT MONO (-615 3160);
DISPLAY INVISIBLE (-615 3160);
FORCEPROP 1 LASTPIN (-625 3150) BN 15
J 2
(-613 3158);
DISPLAY 0.680851 (-613 3158);
PAINT GREEN (-613 3158);
FORCEPROP 2 LAST CDS_LIB standard
J 0
(-675 3150);
DISPLAY INVISIBLE (-675 3150);
FORCEPROP 1 LAST BODY_TYPE PLUMBING
J 2
(-675 3200);
DISPLAY 0.872340 (-675 3200);
PAINT GREEN (-675 3200);
DISPLAY INVISIBLE (-675 3200);
FORCEPROP 1 LAST HDL_TAP TRUE
J 2
(-1000 3025);
DISPLAY 0.872340 (-1000 3025);
DISPLAY INVISIBLE (-1000 3025);
FORCEPROP 1 LAST PATH I75
J 2
(-673 3150);
DISPLAY 0.872340 (-673 3150);
PAINT GREEN (-673 3150);
DISPLAY INVISIBLE (-673 3150);
FORCEADD TAP..1
R 2
(-675 3350);
FORCEPROP 3 LASTPIN (-625 3350) SIG_NAME M_C_CPU1_SA_DQ<19>
J 0
(-615 3360);
DISPLAY 0.659574 (-615 3360);
PAINT MONO (-615 3360);
DISPLAY INVISIBLE (-615 3360);
FORCEPROP 1 LASTPIN (-625 3350) BN 19
J 2
(-613 3358);
DISPLAY 0.680851 (-613 3358);
PAINT GREEN (-613 3358);
FORCEPROP 2 LAST CDS_LIB standard
J 0
(-675 3350);
DISPLAY INVISIBLE (-675 3350);
FORCEPROP 1 LAST BODY_TYPE PLUMBING
J 2
(-675 3400);
DISPLAY 0.872340 (-675 3400);
PAINT GREEN (-675 3400);
DISPLAY INVISIBLE (-675 3400);
FORCEPROP 1 LAST HDL_TAP TRUE
J 2
(-1000 3225);
DISPLAY 0.872340 (-1000 3225);
DISPLAY INVISIBLE (-1000 3225);
FORCEPROP 1 LAST PATH I76
J 2
(-673 3350);
DISPLAY 0.872340 (-673 3350);
PAINT GREEN (-673 3350);
DISPLAY INVISIBLE (-673 3350);
FORCEADD TAP..1
R 2
(-675 3300);
FORCEPROP 3 LASTPIN (-625 3300) SIG_NAME M_C_CPU1_SA_DQ<18>
J 0
(-615 3310);
DISPLAY 0.659574 (-615 3310);
PAINT MONO (-615 3310);
DISPLAY INVISIBLE (-615 3310);
FORCEPROP 1 LASTPIN (-625 3300) BN 18
J 2
(-613 3308);
DISPLAY 0.680851 (-613 3308);
PAINT GREEN (-613 3308);
FORCEPROP 2 LAST CDS_LIB standard
J 0
(-675 3300);
DISPLAY INVISIBLE (-675 3300);
FORCEPROP 1 LAST BODY_TYPE PLUMBING
J 2
(-675 3350);
DISPLAY 0.872340 (-675 3350);
PAINT GREEN (-675 3350);
DISPLAY INVISIBLE (-675 3350);
FORCEPROP 1 LAST HDL_TAP TRUE
J 2
(-1000 3175);
DISPLAY 0.872340 (-1000 3175);
DISPLAY INVISIBLE (-1000 3175);
FORCEPROP 1 LAST PATH I77
J 2
(-673 3300);
DISPLAY 0.872340 (-673 3300);
PAINT GREEN (-673 3300);
DISPLAY INVISIBLE (-673 3300);
FORCEADD TAP..1
R 2
(-675 3250);
FORCEPROP 3 LASTPIN (-625 3250) SIG_NAME M_C_CPU1_SA_DQ<17>
J 0
(-615 3260);
DISPLAY 0.659574 (-615 3260);
PAINT MONO (-615 3260);
DISPLAY INVISIBLE (-615 3260);
FORCEPROP 1 LASTPIN (-625 3250) BN 17
J 2
(-613 3258);
DISPLAY 0.680851 (-613 3258);
PAINT GREEN (-613 3258);
FORCEPROP 2 LAST CDS_LIB standard
J 0
(-675 3250);
DISPLAY INVISIBLE (-675 3250);
FORCEPROP 1 LAST BODY_TYPE PLUMBING
J 2
(-675 3300);
DISPLAY 0.872340 (-675 3300);
PAINT GREEN (-675 3300);
DISPLAY INVISIBLE (-675 3300);
FORCEPROP 1 LAST HDL_TAP TRUE
J 2
(-1000 3125);
DISPLAY 0.872340 (-1000 3125);
DISPLAY INVISIBLE (-1000 3125);
FORCEPROP 1 LAST PATH I78
J 2
(-673 3250);
DISPLAY 0.872340 (-673 3250);
PAINT GREEN (-673 3250);
DISPLAY INVISIBLE (-673 3250);
FORCEADD TAP..1
R 2
(-675 3450);
FORCEPROP 3 LASTPIN (-625 3450) SIG_NAME M_C_CPU1_SA_DQ<21>
J 0
(-615 3460);
DISPLAY 0.659574 (-615 3460);
PAINT MONO (-615 3460);
DISPLAY INVISIBLE (-615 3460);
FORCEPROP 1 LASTPIN (-625 3450) BN 21
J 2
(-613 3458);
DISPLAY 0.680851 (-613 3458);
PAINT GREEN (-613 3458);
FORCEPROP 2 LAST CDS_LIB standard
J 0
(-675 3450);
DISPLAY INVISIBLE (-675 3450);
FORCEPROP 1 LAST BODY_TYPE PLUMBING
J 2
(-675 3500);
DISPLAY 0.872340 (-675 3500);
PAINT GREEN (-675 3500);
DISPLAY INVISIBLE (-675 3500);
FORCEPROP 1 LAST HDL_TAP TRUE
J 2
(-1000 3325);
DISPLAY 0.872340 (-1000 3325);
DISPLAY INVISIBLE (-1000 3325);
FORCEPROP 1 LAST PATH I79
J 2
(-673 3450);
DISPLAY 0.872340 (-673 3450);
PAINT GREEN (-673 3450);
DISPLAY INVISIBLE (-673 3450);
FORCEADD TAP..1
R 2
(-675 100);
FORCEPROP 3 LASTPIN (-625 100) SIG_NAME M_C_CPU1_SB_CB<2>
J 0
(-615 110);
DISPLAY 0.659574 (-615 110);
PAINT MONO (-615 110);
DISPLAY INVISIBLE (-615 110);
FORCEPROP 1 LASTPIN (-625 100) BN 2
J 2
(-613 108);
DISPLAY 0.680851 (-613 108);
PAINT GREEN (-613 108);
FORCEPROP 2 LAST CDS_LIB standard
J 0
(-675 100);
DISPLAY INVISIBLE (-675 100);
FORCEPROP 1 LAST BODY_TYPE PLUMBING
J 2
(-675 150);
DISPLAY 0.872340 (-675 150);
PAINT GREEN (-675 150);
DISPLAY INVISIBLE (-675 150);
FORCEPROP 1 LAST HDL_TAP TRUE
J 2
(-1000 -25);
DISPLAY 0.872340 (-1000 -25);
DISPLAY INVISIBLE (-1000 -25);
FORCEPROP 1 LAST PATH I8
J 2
(-673 100);
DISPLAY 0.872340 (-673 100);
PAINT GREEN (-673 100);
DISPLAY INVISIBLE (-673 100);
FORCEADD TAP..1
R 2
(-675 3400);
FORCEPROP 3 LASTPIN (-625 3400) SIG_NAME M_C_CPU1_SA_DQ<20>
J 0
(-615 3410);
DISPLAY 0.659574 (-615 3410);
PAINT MONO (-615 3410);
DISPLAY INVISIBLE (-615 3410);
FORCEPROP 1 LASTPIN (-625 3400) BN 20
J 2
(-613 3408);
DISPLAY 0.680851 (-613 3408);
PAINT GREEN (-613 3408);
FORCEPROP 2 LAST CDS_LIB standard
J 0
(-675 3400);
DISPLAY INVISIBLE (-675 3400);
FORCEPROP 1 LAST BODY_TYPE PLUMBING
J 2
(-675 3450);
DISPLAY 0.872340 (-675 3450);
PAINT GREEN (-675 3450);
DISPLAY INVISIBLE (-675 3450);
FORCEPROP 1 LAST HDL_TAP TRUE
J 2
(-1000 3275);
DISPLAY 0.872340 (-1000 3275);
DISPLAY INVISIBLE (-1000 3275);
FORCEPROP 1 LAST PATH I80
J 2
(-673 3400);
DISPLAY 0.872340 (-673 3400);
PAINT GREEN (-673 3400);
DISPLAY INVISIBLE (-673 3400);
FORCEADD TAP..1
R 2
(-675 3500);
FORCEPROP 3 LASTPIN (-625 3500) SIG_NAME M_C_CPU1_SA_DQ<22>
J 0
(-615 3510);
DISPLAY 0.659574 (-615 3510);
PAINT MONO (-615 3510);
DISPLAY INVISIBLE (-615 3510);
FORCEPROP 1 LASTPIN (-625 3500) BN 22
J 2
(-613 3508);
DISPLAY 0.680851 (-613 3508);
PAINT GREEN (-613 3508);
FORCEPROP 2 LAST CDS_LIB standard
J 0
(-675 3500);
DISPLAY INVISIBLE (-675 3500);
FORCEPROP 1 LAST BODY_TYPE PLUMBING
J 2
(-675 3550);
DISPLAY 0.872340 (-675 3550);
PAINT GREEN (-675 3550);
DISPLAY INVISIBLE (-675 3550);
FORCEPROP 1 LAST HDL_TAP TRUE
J 2
(-1000 3375);
DISPLAY 0.872340 (-1000 3375);
DISPLAY INVISIBLE (-1000 3375);
FORCEPROP 1 LAST PATH I81
J 2
(-673 3500);
DISPLAY 0.872340 (-673 3500);
PAINT GREEN (-673 3500);
DISPLAY INVISIBLE (-673 3500);
FORCEADD TAP..1
R 2
(-675 3600);
FORCEPROP 3 LASTPIN (-625 3600) SIG_NAME M_C_CPU1_SA_DQ<24>
J 0
(-615 3610);
DISPLAY 0.659574 (-615 3610);
PAINT MONO (-615 3610);
DISPLAY INVISIBLE (-615 3610);
FORCEPROP 1 LASTPIN (-625 3600) BN 24
J 2
(-613 3608);
DISPLAY 0.680851 (-613 3608);
PAINT GREEN (-613 3608);
FORCEPROP 2 LAST CDS_LIB standard
J 0
(-675 3600);
DISPLAY INVISIBLE (-675 3600);
FORCEPROP 1 LAST BODY_TYPE PLUMBING
J 2
(-675 3650);
DISPLAY 0.872340 (-675 3650);
PAINT GREEN (-675 3650);
DISPLAY INVISIBLE (-675 3650);
FORCEPROP 1 LAST HDL_TAP TRUE
J 2
(-1000 3475);
DISPLAY 0.872340 (-1000 3475);
DISPLAY INVISIBLE (-1000 3475);
FORCEPROP 1 LAST PATH I82
J 2
(-673 3600);
DISPLAY 0.872340 (-673 3600);
PAINT GREEN (-673 3600);
DISPLAY INVISIBLE (-673 3600);
FORCEADD TAP..1
R 2
(-675 3550);
FORCEPROP 3 LASTPIN (-625 3550) SIG_NAME M_C_CPU1_SA_DQ<23>
J 0
(-615 3560);
DISPLAY 0.659574 (-615 3560);
PAINT MONO (-615 3560);
DISPLAY INVISIBLE (-615 3560);
FORCEPROP 1 LASTPIN (-625 3550) BN 23
J 2
(-613 3558);
DISPLAY 0.680851 (-613 3558);
PAINT GREEN (-613 3558);
FORCEPROP 2 LAST CDS_LIB standard
J 0
(-675 3550);
DISPLAY INVISIBLE (-675 3550);
FORCEPROP 1 LAST BODY_TYPE PLUMBING
J 2
(-675 3600);
DISPLAY 0.872340 (-675 3600);
PAINT GREEN (-675 3600);
DISPLAY INVISIBLE (-675 3600);
FORCEPROP 1 LAST HDL_TAP TRUE
J 2
(-1000 3425);
DISPLAY 0.872340 (-1000 3425);
DISPLAY INVISIBLE (-1000 3425);
FORCEPROP 1 LAST PATH I83
J 2
(-673 3550);
DISPLAY 0.872340 (-673 3550);
PAINT GREEN (-673 3550);
DISPLAY INVISIBLE (-673 3550);
FORCEADD TAP..1
R 2
(-675 3750);
FORCEPROP 3 LASTPIN (-625 3750) SIG_NAME M_C_CPU1_SA_DQ<27>
J 0
(-615 3760);
DISPLAY 0.659574 (-615 3760);
PAINT MONO (-615 3760);
DISPLAY INVISIBLE (-615 3760);
FORCEPROP 1 LASTPIN (-625 3750) BN 27
J 2
(-613 3758);
DISPLAY 0.680851 (-613 3758);
PAINT GREEN (-613 3758);
FORCEPROP 2 LAST CDS_LIB standard
J 0
(-675 3750);
DISPLAY INVISIBLE (-675 3750);
FORCEPROP 1 LAST BODY_TYPE PLUMBING
J 2
(-675 3800);
DISPLAY 0.872340 (-675 3800);
PAINT GREEN (-675 3800);
DISPLAY INVISIBLE (-675 3800);
FORCEPROP 1 LAST HDL_TAP TRUE
J 2
(-1000 3625);
DISPLAY 0.872340 (-1000 3625);
DISPLAY INVISIBLE (-1000 3625);
FORCEPROP 1 LAST PATH I84
J 2
(-673 3750);
DISPLAY 0.872340 (-673 3750);
PAINT GREEN (-673 3750);
DISPLAY INVISIBLE (-673 3750);
FORCEADD TAP..1
R 2
(-675 3700);
FORCEPROP 3 LASTPIN (-625 3700) SIG_NAME M_C_CPU1_SA_DQ<26>
J 0
(-615 3710);
DISPLAY 0.659574 (-615 3710);
PAINT MONO (-615 3710);
DISPLAY INVISIBLE (-615 3710);
FORCEPROP 1 LASTPIN (-625 3700) BN 26
J 2
(-613 3708);
DISPLAY 0.680851 (-613 3708);
PAINT GREEN (-613 3708);
FORCEPROP 2 LAST CDS_LIB standard
J 0
(-675 3700);
DISPLAY INVISIBLE (-675 3700);
FORCEPROP 1 LAST BODY_TYPE PLUMBING
J 2
(-675 3750);
DISPLAY 0.872340 (-675 3750);
PAINT GREEN (-675 3750);
DISPLAY INVISIBLE (-675 3750);
FORCEPROP 1 LAST HDL_TAP TRUE
J 2
(-1000 3575);
DISPLAY 0.872340 (-1000 3575);
DISPLAY INVISIBLE (-1000 3575);
FORCEPROP 1 LAST PATH I85
J 2
(-673 3700);
DISPLAY 0.872340 (-673 3700);
PAINT GREEN (-673 3700);
DISPLAY INVISIBLE (-673 3700);
FORCEADD TAP..1
R 2
(-675 3650);
FORCEPROP 3 LASTPIN (-625 3650) SIG_NAME M_C_CPU1_SA_DQ<25>
J 0
(-615 3660);
DISPLAY 0.659574 (-615 3660);
PAINT MONO (-615 3660);
DISPLAY INVISIBLE (-615 3660);
FORCEPROP 1 LASTPIN (-625 3650) BN 25
J 2
(-613 3658);
DISPLAY 0.680851 (-613 3658);
PAINT GREEN (-613 3658);
FORCEPROP 2 LAST CDS_LIB standard
J 0
(-675 3650);
DISPLAY INVISIBLE (-675 3650);
FORCEPROP 1 LAST BODY_TYPE PLUMBING
J 2
(-675 3700);
DISPLAY 0.872340 (-675 3700);
PAINT GREEN (-675 3700);
DISPLAY INVISIBLE (-675 3700);
FORCEPROP 1 LAST HDL_TAP TRUE
J 2
(-1000 3525);
DISPLAY 0.872340 (-1000 3525);
DISPLAY INVISIBLE (-1000 3525);
FORCEPROP 1 LAST PATH I86
J 2
(-673 3650);
DISPLAY 0.872340 (-673 3650);
PAINT GREEN (-673 3650);
DISPLAY INVISIBLE (-673 3650);
FORCEADD TAP..1
R 2
(-675 3850);
FORCEPROP 3 LASTPIN (-625 3850) SIG_NAME M_C_CPU1_SA_DQ<29>
J 0
(-615 3860);
DISPLAY 0.659574 (-615 3860);
PAINT MONO (-615 3860);
DISPLAY INVISIBLE (-615 3860);
FORCEPROP 1 LASTPIN (-625 3850) BN 29
J 2
(-613 3858);
DISPLAY 0.680851 (-613 3858);
PAINT GREEN (-613 3858);
FORCEPROP 2 LAST CDS_LIB standard
J 0
(-675 3850);
DISPLAY INVISIBLE (-675 3850);
FORCEPROP 1 LAST BODY_TYPE PLUMBING
J 2
(-675 3900);
DISPLAY 0.872340 (-675 3900);
PAINT GREEN (-675 3900);
DISPLAY INVISIBLE (-675 3900);
FORCEPROP 1 LAST HDL_TAP TRUE
J 2
(-1000 3725);
DISPLAY 0.872340 (-1000 3725);
DISPLAY INVISIBLE (-1000 3725);
FORCEPROP 1 LAST PATH I87
J 2
(-673 3850);
DISPLAY 0.872340 (-673 3850);
PAINT GREEN (-673 3850);
DISPLAY INVISIBLE (-673 3850);
FORCEADD TAP..1
R 2
(-675 3800);
FORCEPROP 3 LASTPIN (-625 3800) SIG_NAME M_C_CPU1_SA_DQ<28>
J 0
(-615 3810);
DISPLAY 0.659574 (-615 3810);
PAINT MONO (-615 3810);
DISPLAY INVISIBLE (-615 3810);
FORCEPROP 1 LASTPIN (-625 3800) BN 28
J 2
(-613 3808);
DISPLAY 0.680851 (-613 3808);
PAINT GREEN (-613 3808);
FORCEPROP 2 LAST CDS_LIB standard
J 0
(-675 3800);
DISPLAY INVISIBLE (-675 3800);
FORCEPROP 1 LAST BODY_TYPE PLUMBING
J 2
(-675 3850);
DISPLAY 0.872340 (-675 3850);
PAINT GREEN (-675 3850);
DISPLAY INVISIBLE (-675 3850);
FORCEPROP 1 LAST HDL_TAP TRUE
J 2
(-1000 3675);
DISPLAY 0.872340 (-1000 3675);
DISPLAY INVISIBLE (-1000 3675);
FORCEPROP 1 LAST PATH I88
J 2
(-673 3800);
DISPLAY 0.872340 (-673 3800);
PAINT GREEN (-673 3800);
DISPLAY INVISIBLE (-673 3800);
FORCEADD TAP..1
R 2
(-675 3950);
FORCEPROP 3 LASTPIN (-625 3950) SIG_NAME M_C_CPU1_SA_DQ<31>
J 0
(-615 3960);
DISPLAY 0.659574 (-615 3960);
PAINT MONO (-615 3960);
DISPLAY INVISIBLE (-615 3960);
FORCEPROP 1 LASTPIN (-625 3950) BN 31
J 2
(-613 3958);
DISPLAY 0.680851 (-613 3958);
PAINT GREEN (-613 3958);
FORCEPROP 2 LAST CDS_LIB standard
J 0
(-675 3950);
DISPLAY INVISIBLE (-675 3950);
FORCEPROP 1 LAST BODY_TYPE PLUMBING
J 2
(-675 4000);
DISPLAY 0.872340 (-675 4000);
PAINT GREEN (-675 4000);
DISPLAY INVISIBLE (-675 4000);
FORCEPROP 1 LAST HDL_TAP TRUE
J 2
(-1000 3825);
DISPLAY 0.872340 (-1000 3825);
DISPLAY INVISIBLE (-1000 3825);
FORCEPROP 1 LAST PATH I89
J 2
(-673 3950);
DISPLAY 0.872340 (-673 3950);
PAINT GREEN (-673 3950);
DISPLAY INVISIBLE (-673 3950);
FORCEADD TAP..1
R 2
(-675 150);
FORCEPROP 3 LASTPIN (-625 150) SIG_NAME M_C_CPU1_SB_CB<3>
J 0
(-615 160);
DISPLAY 0.659574 (-615 160);
PAINT MONO (-615 160);
DISPLAY INVISIBLE (-615 160);
FORCEPROP 1 LASTPIN (-625 150) BN 3
J 2
(-613 158);
DISPLAY 0.680851 (-613 158);
PAINT GREEN (-613 158);
FORCEPROP 2 LAST CDS_LIB standard
J 0
(-675 150);
DISPLAY INVISIBLE (-675 150);
FORCEPROP 1 LAST BODY_TYPE PLUMBING
J 2
(-675 200);
DISPLAY 0.872340 (-675 200);
PAINT GREEN (-675 200);
DISPLAY INVISIBLE (-675 200);
FORCEPROP 1 LAST HDL_TAP TRUE
J 2
(-1000 25);
DISPLAY 0.872340 (-1000 25);
DISPLAY INVISIBLE (-1000 25);
FORCEPROP 1 LAST PATH I9
J 2
(-673 150);
DISPLAY 0.872340 (-673 150);
PAINT GREEN (-673 150);
DISPLAY INVISIBLE (-673 150);
FORCEADD TAP..1
R 2
(-675 3900);
FORCEPROP 3 LASTPIN (-625 3900) SIG_NAME M_C_CPU1_SA_DQ<30>
J 0
(-615 3910);
DISPLAY 0.659574 (-615 3910);
PAINT MONO (-615 3910);
DISPLAY INVISIBLE (-615 3910);
FORCEPROP 1 LASTPIN (-625 3900) BN 30
J 2
(-613 3908);
DISPLAY 0.680851 (-613 3908);
PAINT GREEN (-613 3908);
FORCEPROP 2 LAST CDS_LIB standard
J 0
(-675 3900);
DISPLAY INVISIBLE (-675 3900);
FORCEPROP 1 LAST BODY_TYPE PLUMBING
J 2
(-675 3950);
DISPLAY 0.872340 (-675 3950);
PAINT GREEN (-675 3950);
DISPLAY INVISIBLE (-675 3950);
FORCEPROP 1 LAST HDL_TAP TRUE
J 2
(-1000 3775);
DISPLAY 0.872340 (-1000 3775);
DISPLAY INVISIBLE (-1000 3775);
FORCEPROP 1 LAST PATH I90
J 2
(-673 3900);
DISPLAY 0.872340 (-673 3900);
PAINT GREEN (-673 3900);
DISPLAY INVISIBLE (-673 3900);
FORCEADD SOCKET4677_AZIF0045P001C01CS..10
(1050 1850);
FORCEPROP 1 LAST PART_NUMBER DGA^7000023
J 0
(-50 4200);
DISPLAY 0.723404 (-50 4200);
PAINT GREEN (-50 4200);
DISPLAY INVISIBLE (-50 4200);
FORCEPROP 2 LAST PART_TYPE SMLF
J 0
(-50 4375);
DISPLAY 1.021277 (-50 4375);
FORCEPROP 1 LAST MATERIAL IO
J 0
(-50 4125);
DISPLAY 0.723404 (-50 4125);
PAINT GREEN (-50 4125);
FORCEPROP 2 LAST VALUE SOCKET4677_AZIF0045-P001C01CS
J 0
(-50 4325);
DISPLAY 1.021277 (-50 4325);
FORCEPROP 1 LAST $LOCATION U1
J 0
(-50 4275);
DISPLAY 0.723404 (-50 4275);
PAINT GREEN (-50 4275);
FORCEPROP 0 LASTPIN (2275 0) $PN AC48
J 0
(2285 10);
DISPLAY 0.680851 (2285 10);
PAINT MONO (2285 10);
FORCEPROP 0 LASTPIN (2275 50) $PN AD47
J 0
(2285 60);
DISPLAY 0.680851 (2285 60);
PAINT MONO (2285 60);
FORCEPROP 0 LASTPIN (2275 -250) $PN AT47
J 0
(2285 -240);
DISPLAY 0.680851 (2285 -240);
PAINT MONO (2285 -240);
FORCEPROP 0 LASTPIN (2275 -150) $PN AG48
J 0
(2285 -140);
DISPLAY 0.680851 (2285 -140);
PAINT MONO (2285 -140);
FORCEPROP 0 LASTPIN (2275 -100) $PN AF47
J 0
(2285 -90);
DISPLAY 0.680851 (2285 -90);
PAINT MONO (2285 -90);
FORCEPROP 0 LASTPIN (-175 -250) $PN AB49
J 2
(-185 -240);
DISPLAY 0.680851 (-185 -240);
PAINT MONO (-185 -240);
FORCEPROP 0 LASTPIN (-175 -200) $PN AF49
J 2
(-185 -190);
DISPLAY 0.680851 (-185 -190);
PAINT MONO (-185 -190);
FORCEPROP 0 LASTPIN (-175 -150) $PN AD49
J 2
(-185 -140);
DISPLAY 0.680851 (-185 -140);
PAINT MONO (-185 -140);
FORCEPROP 0 LASTPIN (-175 -100) $PN AH49
J 2
(-185 -90);
DISPLAY 0.680851 (-185 -90);
PAINT MONO (-185 -90);
FORCEPROP 0 LASTPIN (2275 1350) $PN R52
J 0
(2285 1360);
DISPLAY 0.680851 (2285 1360);
PAINT MONO (2285 1360);
FORCEPROP 0 LASTPIN (2275 1400) $PN AA52
J 0
(2285 1410);
DISPLAY 0.680851 (2285 1410);
PAINT MONO (2285 1410);
FORCEPROP 0 LASTPIN (2275 1450) $PN T51
J 0
(2285 1460);
DISPLAY 0.680851 (2285 1460);
PAINT MONO (2285 1460);
FORCEPROP 0 LASTPIN (2275 1500) $PN Y51
J 0
(2285 1510);
DISPLAY 0.680851 (2285 1510);
PAINT MONO (2285 1510);
FORCEPROP 0 LASTPIN (2275 1550) $PN U50
J 0
(2285 1560);
DISPLAY 0.680851 (2285 1560);
PAINT MONO (2285 1560);
FORCEPROP 0 LASTPIN (2275 1600) $PN W50
J 0
(2285 1610);
DISPLAY 0.680851 (2285 1610);
PAINT MONO (2285 1610);
FORCEPROP 0 LASTPIN (2275 1650) $PN U48
J 0
(2285 1660);
DISPLAY 0.680851 (2285 1660);
PAINT MONO (2285 1660);
FORCEPROP 0 LASTPIN (-175 2400) $PN U78
J 2
(-185 2410);
DISPLAY 0.680851 (-185 2410);
PAINT MONO (-185 2410);
FORCEPROP 0 LASTPIN (-175 2450) $PN T77
J 2
(-185 2460);
DISPLAY 0.680851 (-185 2460);
PAINT MONO (-185 2460);
FORCEPROP 0 LASTPIN (-175 2500) $PN W78
J 2
(-185 2510);
DISPLAY 0.680851 (-185 2510);
PAINT MONO (-185 2510);
FORCEPROP 0 LASTPIN (-175 2550) $PN Y77
J 2
(-185 2560);
DISPLAY 0.680851 (-185 2560);
PAINT MONO (-185 2560);
FORCEPROP 0 LASTPIN (-175 2600) $PN T75
J 2
(-185 2610);
DISPLAY 0.680851 (-185 2610);
PAINT MONO (-185 2610);
FORCEPROP 0 LASTPIN (-175 2650) $PN U74
J 2
(-185 2660);
DISPLAY 0.680851 (-185 2660);
PAINT MONO (-185 2660);
FORCEPROP 0 LASTPIN (-175 2700) $PN Y75
J 2
(-185 2710);
DISPLAY 0.680851 (-185 2710);
PAINT MONO (-185 2710);
FORCEPROP 0 LASTPIN (-175 2750) $PN W74
J 2
(-185 2760);
DISPLAY 0.680851 (-185 2760);
PAINT MONO (-185 2760);
FORCEPROP 0 LASTPIN (-175 2800) $PN AD69
J 2
(-185 2810);
DISPLAY 0.680851 (-185 2810);
PAINT MONO (-185 2810);
FORCEPROP 0 LASTPIN (-175 2850) $PN AC68
J 2
(-185 2860);
DISPLAY 0.680851 (-185 2860);
PAINT MONO (-185 2860);
FORCEPROP 0 LASTPIN (-175 2900) $PN AF69
J 2
(-185 2910);
DISPLAY 0.680851 (-185 2910);
PAINT MONO (-185 2910);
FORCEPROP 0 LASTPIN (-175 2950) $PN AG68
J 2
(-185 2960);
DISPLAY 0.680851 (-185 2960);
PAINT MONO (-185 2960);
FORCEPROP 0 LASTPIN (-175 3000) $PN AC66
J 2
(-185 3010);
DISPLAY 0.680851 (-185 3010);
PAINT MONO (-185 3010);
FORCEPROP 0 LASTPIN (-175 3050) $PN AD65
J 2
(-185 3060);
DISPLAY 0.680851 (-185 3060);
PAINT MONO (-185 3060);
FORCEPROP 0 LASTPIN (-175 3100) $PN AG66
J 2
(-185 3110);
DISPLAY 0.680851 (-185 3110);
PAINT MONO (-185 3110);
FORCEPROP 0 LASTPIN (-175 3150) $PN AF65
J 2
(-185 3160);
DISPLAY 0.680851 (-185 3160);
PAINT MONO (-185 3160);
FORCEPROP 0 LASTPIN (-175 3200) $PN U66
J 2
(-185 3210);
DISPLAY 0.680851 (-185 3210);
PAINT MONO (-185 3210);
FORCEPROP 0 LASTPIN (-175 3250) $PN T65
J 2
(-185 3260);
DISPLAY 0.680851 (-185 3260);
PAINT MONO (-185 3260);
FORCEPROP 0 LASTPIN (-175 3300) $PN W66
J 2
(-185 3310);
DISPLAY 0.680851 (-185 3310);
PAINT MONO (-185 3310);
FORCEPROP 0 LASTPIN (-175 3350) $PN Y65
J 2
(-185 3360);
DISPLAY 0.680851 (-185 3360);
PAINT MONO (-185 3360);
FORCEPROP 0 LASTPIN (-175 3400) $PN T63
J 2
(-185 3410);
DISPLAY 0.680851 (-185 3410);
PAINT MONO (-185 3410);
FORCEPROP 0 LASTPIN (-175 3450) $PN U62
J 2
(-185 3460);
DISPLAY 0.680851 (-185 3460);
PAINT MONO (-185 3460);
FORCEPROP 0 LASTPIN (-175 3500) $PN Y63
J 2
(-185 3510);
DISPLAY 0.680851 (-185 3510);
PAINT MONO (-185 3510);
FORCEPROP 0 LASTPIN (-175 3550) $PN W62
J 2
(-185 3560);
DISPLAY 0.680851 (-185 3560);
PAINT MONO (-185 3560);
FORCEPROP 0 LASTPIN (-175 3600) $PN AD63
J 2
(-185 3610);
DISPLAY 0.680851 (-185 3610);
PAINT MONO (-185 3610);
FORCEPROP 0 LASTPIN (-175 3650) $PN AC62
J 2
(-185 3660);
DISPLAY 0.680851 (-185 3660);
PAINT MONO (-185 3660);
FORCEPROP 0 LASTPIN (-175 3700) $PN AF63
J 2
(-185 3710);
DISPLAY 0.680851 (-185 3710);
PAINT MONO (-185 3710);
FORCEPROP 0 LASTPIN (-175 3750) $PN AG62
J 2
(-185 3760);
DISPLAY 0.680851 (-185 3760);
PAINT MONO (-185 3760);
FORCEPROP 0 LASTPIN (-175 3800) $PN AC60
J 2
(-185 3810);
DISPLAY 0.680851 (-185 3810);
PAINT MONO (-185 3810);
FORCEPROP 0 LASTPIN (-175 3850) $PN AD59
J 2
(-185 3860);
DISPLAY 0.680851 (-185 3860);
PAINT MONO (-185 3860);
FORCEPROP 0 LASTPIN (-175 3900) $PN AG60
J 2
(-185 3910);
DISPLAY 0.680851 (-185 3910);
PAINT MONO (-185 3910);
FORCEPROP 0 LASTPIN (-175 3950) $PN AF59
J 2
(-185 3960);
DISPLAY 0.680851 (-185 3960);
PAINT MONO (-185 3960);
FORCEPROP 0 LASTPIN (2275 2950) $PN R76
J 0
(2285 2960);
DISPLAY 0.680851 (2285 2960);
PAINT MONO (2285 2960);
FORCEPROP 0 LASTPIN (2275 3000) $PN AB67
J 0
(2285 3010);
DISPLAY 0.680851 (2285 3010);
PAINT MONO (2285 3010);
FORCEPROP 0 LASTPIN (2275 3050) $PN R64
J 0
(2285 3060);
DISPLAY 0.680851 (2285 3060);
PAINT MONO (2285 3060);
FORCEPROP 0 LASTPIN (2275 3100) $PN AB61
J 0
(2285 3110);
DISPLAY 0.680851 (2285 3110);
PAINT MONO (2285 3110);
FORCEPROP 0 LASTPIN (2275 3150) $PN AD55
J 0
(2285 3160);
DISPLAY 0.680851 (2285 3160);
PAINT MONO (2285 3160);
FORCEPROP 0 LASTPIN (2275 3200) $PN W76
J 0
(2285 3210);
DISPLAY 0.680851 (2285 3210);
PAINT MONO (2285 3210);
FORCEPROP 0 LASTPIN (2275 3250) $PN AH67
J 0
(2285 3260);
DISPLAY 0.680851 (2285 3260);
PAINT MONO (2285 3260);
FORCEPROP 0 LASTPIN (2275 3300) $PN AA64
J 0
(2285 3310);
DISPLAY 0.680851 (2285 3310);
PAINT MONO (2285 3310);
FORCEPROP 0 LASTPIN (2275 3350) $PN AF61
J 0
(2285 3360);
DISPLAY 0.680851 (2285 3360);
PAINT MONO (2285 3360);
FORCEPROP 0 LASTPIN (2275 3400) $PN AH55
J 0
(2285 3410);
DISPLAY 0.680851 (2285 3410);
PAINT MONO (2285 3410);
FORCEPROP 0 LASTPIN (2275 3500) $PN U76
J 0
(2285 3510);
DISPLAY 0.680851 (2285 3510);
PAINT MONO (2285 3510);
FORCEPROP 0 LASTPIN (2275 3550) $PN AD67
J 0
(2285 3560);
DISPLAY 0.680851 (2285 3560);
PAINT MONO (2285 3560);
FORCEPROP 0 LASTPIN (2275 3600) $PN U64
J 0
(2285 3610);
DISPLAY 0.680851 (2285 3610);
PAINT MONO (2285 3610);
FORCEPROP 0 LASTPIN (2275 3650) $PN AD61
J 0
(2285 3660);
DISPLAY 0.680851 (2285 3660);
PAINT MONO (2285 3660);
FORCEPROP 0 LASTPIN (2275 3700) $PN AB55
J 0
(2285 3710);
DISPLAY 0.680851 (2285 3710);
PAINT MONO (2285 3710);
FORCEPROP 0 LASTPIN (2275 3750) $PN AA76
J 0
(2285 3760);
DISPLAY 0.680851 (2285 3760);
PAINT MONO (2285 3760);
FORCEPROP 0 LASTPIN (2275 3800) $PN AF67
J 0
(2285 3810);
DISPLAY 0.680851 (2285 3810);
PAINT MONO (2285 3810);
FORCEPROP 0 LASTPIN (2275 3850) $PN W64
J 0
(2285 3860);
DISPLAY 0.680851 (2285 3860);
PAINT MONO (2285 3860);
FORCEPROP 0 LASTPIN (2275 3900) $PN AH61
J 0
(2285 3910);
DISPLAY 0.680851 (2285 3910);
PAINT MONO (2285 3910);
FORCEPROP 0 LASTPIN (2275 3950) $PN AF55
J 0
(2285 3960);
DISPLAY 0.680851 (2285 3960);
PAINT MONO (2285 3960);
FORCEPROP 0 LASTPIN (-175 2000) $PN AD57
J 2
(-185 2010);
DISPLAY 0.680851 (-185 2010);
PAINT MONO (-185 2010);
FORCEPROP 0 LASTPIN (-175 2050) $PN AC56
J 2
(-185 2060);
DISPLAY 0.680851 (-185 2060);
PAINT MONO (-185 2060);
FORCEPROP 0 LASTPIN (-175 2100) $PN AF57
J 2
(-185 2110);
DISPLAY 0.680851 (-185 2110);
PAINT MONO (-185 2110);
FORCEPROP 0 LASTPIN (-175 2150) $PN AG56
J 2
(-185 2160);
DISPLAY 0.680851 (-185 2160);
PAINT MONO (-185 2160);
FORCEPROP 0 LASTPIN (-175 2200) $PN AC54
J 2
(-185 2210);
DISPLAY 0.680851 (-185 2210);
PAINT MONO (-185 2210);
FORCEPROP 0 LASTPIN (-175 2250) $PN AD53
J 2
(-185 2260);
DISPLAY 0.680851 (-185 2260);
PAINT MONO (-185 2260);
FORCEPROP 0 LASTPIN (-175 2300) $PN AG54
J 2
(-185 2310);
DISPLAY 0.680851 (-185 2310);
PAINT MONO (-185 2310);
FORCEPROP 0 LASTPIN (-175 2350) $PN AF53
J 2
(-185 2360);
DISPLAY 0.680851 (-185 2360);
PAINT MONO (-185 2360);
FORCEPROP 0 LASTPIN (2275 1300) $PN T47
J 0
(2285 1310);
DISPLAY 0.680851 (2285 1310);
PAINT MONO (2285 1310);
FORCEPROP 0 LASTPIN (2275 850) $PN W48
J 0
(2285 860);
DISPLAY 0.680851 (2285 860);
PAINT MONO (2285 860);
FORCEPROP 0 LASTPIN (2275 900) $PN Y47
J 0
(2285 910);
DISPLAY 0.680851 (2285 910);
PAINT MONO (2285 910);
FORCEPROP 0 LASTPIN (2275 950) $PN U41
J 0
(2285 960);
DISPLAY 0.680851 (2285 960);
PAINT MONO (2285 960);
FORCEPROP 0 LASTPIN (2275 1000) $PN W41
J 0
(2285 1010);
DISPLAY 0.680851 (2285 1010);
PAINT MONO (2285 1010);
FORCEPROP 0 LASTPIN (2275 1050) $PN T40
J 0
(2285 1060);
DISPLAY 0.680851 (2285 1060);
PAINT MONO (2285 1060);
FORCEPROP 0 LASTPIN (2275 1100) $PN Y40
J 0
(2285 1110);
DISPLAY 0.680851 (2285 1110);
PAINT MONO (2285 1110);
FORCEPROP 0 LASTPIN (2275 1150) $PN R39
J 0
(2285 1160);
DISPLAY 0.680851 (2285 1160);
PAINT MONO (2285 1160);
FORCEPROP 0 LASTPIN (-175 400) $PN AD38
J 2
(-185 410);
DISPLAY 0.680851 (-185 410);
PAINT MONO (-185 410);
FORCEPROP 0 LASTPIN (-175 450) $PN AC37
J 2
(-185 460);
DISPLAY 0.680851 (-185 460);
PAINT MONO (-185 460);
FORCEPROP 0 LASTPIN (-175 500) $PN AF38
J 2
(-185 510);
DISPLAY 0.680851 (-185 510);
PAINT MONO (-185 510);
FORCEPROP 0 LASTPIN (-175 550) $PN AG37
J 2
(-185 560);
DISPLAY 0.680851 (-185 560);
PAINT MONO (-185 560);
FORCEPROP 0 LASTPIN (-175 600) $PN AC35
J 2
(-185 610);
DISPLAY 0.680851 (-185 610);
PAINT MONO (-185 610);
FORCEPROP 0 LASTPIN (-175 650) $PN AD34
J 2
(-185 660);
DISPLAY 0.680851 (-185 660);
PAINT MONO (-185 660);
FORCEPROP 0 LASTPIN (-175 700) $PN AG35
J 2
(-185 710);
DISPLAY 0.680851 (-185 710);
PAINT MONO (-185 710);
FORCEPROP 0 LASTPIN (-175 750) $PN AF34
J 2
(-185 760);
DISPLAY 0.680851 (-185 760);
PAINT MONO (-185 760);
FORCEPROP 0 LASTPIN (-175 800) $PN AD32
J 2
(-185 810);
DISPLAY 0.680851 (-185 810);
PAINT MONO (-185 810);
FORCEPROP 0 LASTPIN (-175 850) $PN AC31
J 2
(-185 860);
DISPLAY 0.680851 (-185 860);
PAINT MONO (-185 860);
FORCEPROP 0 LASTPIN (-175 900) $PN AF32
J 2
(-185 910);
DISPLAY 0.680851 (-185 910);
PAINT MONO (-185 910);
FORCEPROP 0 LASTPIN (-175 950) $PN AG31
J 2
(-185 960);
DISPLAY 0.680851 (-185 960);
PAINT MONO (-185 960);
FORCEPROP 0 LASTPIN (-175 1000) $PN AC29
J 2
(-185 1010);
DISPLAY 0.680851 (-185 1010);
PAINT MONO (-185 1010);
FORCEPROP 0 LASTPIN (-175 1050) $PN AD28
J 2
(-185 1060);
DISPLAY 0.680851 (-185 1060);
PAINT MONO (-185 1060);
FORCEPROP 0 LASTPIN (-175 1100) $PN AG29
J 2
(-185 1110);
DISPLAY 0.680851 (-185 1110);
PAINT MONO (-185 1110);
FORCEPROP 0 LASTPIN (-175 1150) $PN AF28
J 2
(-185 1160);
DISPLAY 0.680851 (-185 1160);
PAINT MONO (-185 1160);
FORCEPROP 0 LASTPIN (-175 1200) $PN U23
J 2
(-185 1210);
DISPLAY 0.680851 (-185 1210);
PAINT MONO (-185 1210);
FORCEPROP 0 LASTPIN (-175 1250) $PN T22
J 2
(-185 1260);
DISPLAY 0.680851 (-185 1260);
PAINT MONO (-185 1260);
FORCEPROP 0 LASTPIN (-175 1300) $PN W23
J 2
(-185 1310);
DISPLAY 0.680851 (-185 1310);
PAINT MONO (-185 1310);
FORCEPROP 0 LASTPIN (-175 1350) $PN Y22
J 2
(-185 1360);
DISPLAY 0.680851 (-185 1360);
PAINT MONO (-185 1360);
FORCEPROP 0 LASTPIN (-175 1400) $PN T20
J 2
(-185 1410);
DISPLAY 0.680851 (-185 1410);
PAINT MONO (-185 1410);
FORCEPROP 0 LASTPIN (-175 1450) $PN U19
J 2
(-185 1460);
DISPLAY 0.680851 (-185 1460);
PAINT MONO (-185 1460);
FORCEPROP 0 LASTPIN (-175 1500) $PN Y20
J 2
(-185 1510);
DISPLAY 0.680851 (-185 1510);
PAINT MONO (-185 1510);
FORCEPROP 0 LASTPIN (-175 1550) $PN W19
J 2
(-185 1560);
DISPLAY 0.680851 (-185 1560);
PAINT MONO (-185 1560);
FORCEPROP 0 LASTPIN (-175 1600) $PN AD20
J 2
(-185 1610);
DISPLAY 0.680851 (-185 1610);
PAINT MONO (-185 1610);
FORCEPROP 0 LASTPIN (-175 1650) $PN AC19
J 2
(-185 1660);
DISPLAY 0.680851 (-185 1660);
PAINT MONO (-185 1660);
FORCEPROP 0 LASTPIN (-175 1700) $PN AF20
J 2
(-185 1710);
DISPLAY 0.680851 (-185 1710);
PAINT MONO (-185 1710);
FORCEPROP 0 LASTPIN (-175 1750) $PN AG19
J 2
(-185 1760);
DISPLAY 0.680851 (-185 1760);
PAINT MONO (-185 1760);
FORCEPROP 0 LASTPIN (-175 1800) $PN AA17
J 2
(-185 1810);
DISPLAY 0.680851 (-185 1810);
PAINT MONO (-185 1810);
FORCEPROP 0 LASTPIN (-175 1850) $PN AG17
J 2
(-185 1860);
DISPLAY 0.680851 (-185 1860);
PAINT MONO (-185 1860);
FORCEPROP 0 LASTPIN (-175 1900) $PN AC17
J 2
(-185 1910);
DISPLAY 0.680851 (-185 1910);
PAINT MONO (-185 1910);
FORCEPROP 0 LASTPIN (-175 1950) $PN AJ17
J 2
(-185 1960);
DISPLAY 0.680851 (-185 1960);
PAINT MONO (-185 1960);
FORCEPROP 0 LASTPIN (2275 1800) $PN AB36
J 0
(2285 1810);
DISPLAY 0.680851 (2285 1810);
PAINT MONO (2285 1810);
FORCEPROP 0 LASTPIN (2275 1850) $PN AB30
J 0
(2285 1860);
DISPLAY 0.680851 (2285 1860);
PAINT MONO (2285 1860);
FORCEPROP 0 LASTPIN (2275 1900) $PN R21
J 0
(2285 1910);
DISPLAY 0.680851 (2285 1910);
PAINT MONO (2285 1910);
FORCEPROP 0 LASTPIN (2275 1950) $PN AB18
J 0
(2285 1960);
DISPLAY 0.680851 (2285 1960);
PAINT MONO (2285 1960);
FORCEPROP 0 LASTPIN (2275 2000) $PN W33
J 0
(2285 2010);
DISPLAY 0.680851 (2285 2010);
PAINT MONO (2285 2010);
FORCEPROP 0 LASTPIN (2275 2050) $PN AF36
J 0
(2285 2060);
DISPLAY 0.680851 (2285 2060);
PAINT MONO (2285 2060);
FORCEPROP 0 LASTPIN (2275 2100) $PN AF30
J 0
(2285 2110);
DISPLAY 0.680851 (2285 2110);
PAINT MONO (2285 2110);
FORCEPROP 0 LASTPIN (2275 2150) $PN W21
J 0
(2285 2160);
DISPLAY 0.680851 (2285 2160);
PAINT MONO (2285 2160);
FORCEPROP 0 LASTPIN (2275 2200) $PN AF18
J 0
(2285 2210);
DISPLAY 0.680851 (2285 2210);
PAINT MONO (2285 2210);
FORCEPROP 0 LASTPIN (2275 2250) $PN R33
J 0
(2285 2260);
DISPLAY 0.680851 (2285 2260);
PAINT MONO (2285 2260);
FORCEPROP 0 LASTPIN (2275 2350) $PN AD36
J 0
(2285 2360);
DISPLAY 0.680851 (2285 2360);
PAINT MONO (2285 2360);
FORCEPROP 0 LASTPIN (2275 2400) $PN AD30
J 0
(2285 2410);
DISPLAY 0.680851 (2285 2410);
PAINT MONO (2285 2410);
FORCEPROP 0 LASTPIN (2275 2450) $PN U21
J 0
(2285 2460);
DISPLAY 0.680851 (2285 2460);
PAINT MONO (2285 2460);
FORCEPROP 0 LASTPIN (2275 2500) $PN AD18
J 0
(2285 2510);
DISPLAY 0.680851 (2285 2510);
PAINT MONO (2285 2510);
FORCEPROP 0 LASTPIN (2275 2550) $PN AA33
J 0
(2285 2560);
DISPLAY 0.680851 (2285 2560);
PAINT MONO (2285 2560);
FORCEPROP 0 LASTPIN (2275 2600) $PN AH36
J 0
(2285 2610);
DISPLAY 0.680851 (2285 2610);
PAINT MONO (2285 2610);
FORCEPROP 0 LASTPIN (2275 2650) $PN AH30
J 0
(2285 2660);
DISPLAY 0.680851 (2285 2660);
PAINT MONO (2285 2660);
FORCEPROP 0 LASTPIN (2275 2700) $PN AA21
J 0
(2285 2710);
DISPLAY 0.680851 (2285 2710);
PAINT MONO (2285 2710);
FORCEPROP 0 LASTPIN (2275 2750) $PN AH18
J 0
(2285 2760);
DISPLAY 0.680851 (2285 2760);
PAINT MONO (2285 2760);
FORCEPROP 0 LASTPIN (2275 2800) $PN U33
J 0
(2285 2810);
DISPLAY 0.680851 (2285 2810);
PAINT MONO (2285 2810);
FORCEPROP 0 LASTPIN (-175 0) $PN T32
J 2
(-185 10);
DISPLAY 0.680851 (-185 10);
PAINT MONO (-185 10);
FORCEPROP 0 LASTPIN (-175 50) $PN U31
J 2
(-185 60);
DISPLAY 0.680851 (-185 60);
PAINT MONO (-185 60);
FORCEPROP 0 LASTPIN (-175 100) $PN Y32
J 2
(-185 110);
DISPLAY 0.680851 (-185 110);
PAINT MONO (-185 110);
FORCEPROP 0 LASTPIN (-175 150) $PN W31
J 2
(-185 160);
DISPLAY 0.680851 (-185 160);
PAINT MONO (-185 160);
FORCEPROP 0 LASTPIN (-175 200) $PN U35
J 2
(-185 210);
DISPLAY 0.680851 (-185 210);
PAINT MONO (-185 210);
FORCEPROP 0 LASTPIN (-175 250) $PN T34
J 2
(-185 260);
DISPLAY 0.680851 (-185 260);
PAINT MONO (-185 260);
FORCEPROP 0 LASTPIN (-175 300) $PN W35
J 2
(-185 310);
DISPLAY 0.680851 (-185 310);
PAINT MONO (-185 310);
FORCEPROP 0 LASTPIN (-175 350) $PN Y34
J 2
(-185 360);
DISPLAY 0.680851 (-185 360);
PAINT MONO (-185 360);
FORCEPROP 0 LASTPIN (2275 800) $PN AA39
J 0
(2285 810);
DISPLAY 0.680851 (2285 810);
PAINT MONO (2285 810);
FORCEPROP 0 LASTPIN (2275 500) $PN U54
J 0
(2285 510);
DISPLAY 0.680851 (2285 510);
PAINT MONO (2285 510);
FORCEPROP 0 LASTPIN (2275 550) $PN T53
J 0
(2285 560);
DISPLAY 0.680851 (2285 560);
PAINT MONO (2285 560);
FORCEPROP 0 LASTPIN (2275 600) $PN W54
J 0
(2285 610);
DISPLAY 0.680851 (2285 610);
PAINT MONO (2285 610);
FORCEPROP 0 LASTPIN (2275 650) $PN Y53
J 0
(2285 660);
DISPLAY 0.680851 (2285 660);
PAINT MONO (2285 660);
FORCEPROP 0 LASTPIN (2275 200) $PN T38
J 0
(2285 210);
DISPLAY 0.680851 (2285 210);
PAINT MONO (2285 210);
FORCEPROP 0 LASTPIN (2275 250) $PN U37
J 0
(2285 260);
DISPLAY 0.680851 (2285 260);
PAINT MONO (2285 260);
FORCEPROP 0 LASTPIN (2275 300) $PN Y38
J 0
(2285 310);
DISPLAY 0.680851 (2285 310);
PAINT MONO (2285 310);
FORCEPROP 0 LASTPIN (2275 350) $PN W37
J 0
(2285 360);
DISPLAY 0.680851 (2285 360);
PAINT MONO (2285 360);
FORCEPROP 2 LAST CDS_LIB pure_quanta
J 0
(1050 1850);
DISPLAY INVISIBLE (1050 1850);
FORCEPROP 1 LAST NEEDS_NO_SIZE TRUE
J 0
(1050 1850);
DISPLAY 0.723404 (1050 1850);
PAINT GREEN (1050 1850);
DISPLAY INVISIBLE (1050 1850);
FORCEPROP 1 LAST CDS_LMAN_SYM_OUTLINE -1100,2250,1050,-2250
J 0
(1050 1850);
DISPLAY 0.468085 (1050 1850);
PAINT GREEN (1050 1850);
DISPLAY INVISIBLE (1050 1850);
FORCEPROP 2 LAST CDS_LOCATION U1
J 0
(-50 4425);
DISPLAY 1.021277 (-50 4425);
DISPLAY INVISIBLE (-50 4425);
FORCEPROP 0 LAST $SEC 10
J 0
(-50 4425);
DISPLAY 0.680851 (-50 4425);
PAINT MONO (-50 4425);
DISPLAY INVISIBLE (-50 4425);
FORCEPROP 2 LAST CDS_SEC 10
J 0
(-50 4425);
DISPLAY 1.021277 (-50 4425);
DISPLAY INVISIBLE (-50 4425);
FORCEPROP 1 LAST PATH I91
J 0
(1050 1850);
DISPLAY 0.723404 (1050 1850);
PAINT GREEN (1050 1850);
DISPLAY INVISIBLE (1050 1850);
FORCEADD TAP..1
(2750 300);
FORCEPROP 3 LASTPIN (2700 300) SIG_NAME M_C_CPU1_SB_CS_N<2>
J 0
(2710 310);
DISPLAY 0.659574 (2710 310);
PAINT MONO (2710 310);
DISPLAY INVISIBLE (2710 310);
FORCEPROP 1 LASTPIN (2700 300) BN 2
J 0
(2688 308);
DISPLAY 0.680851 (2688 308);
PAINT GREEN (2688 308);
FORCEPROP 2 LAST CDS_LIB standard
J 0
(2750 300);
DISPLAY INVISIBLE (2750 300);
FORCEPROP 1 LAST BODY_TYPE PLUMBING
J 0
(2750 350);
DISPLAY 0.872340 (2750 350);
PAINT GREEN (2750 350);
DISPLAY INVISIBLE (2750 350);
FORCEPROP 1 LAST HDL_TAP TRUE
J 0
(3075 175);
DISPLAY 0.872340 (3075 175);
DISPLAY INVISIBLE (3075 175);
FORCEPROP 1 LAST PATH I92
J 0
(2748 300);
DISPLAY 0.872340 (2748 300);
PAINT GREEN (2748 300);
DISPLAY INVISIBLE (2748 300);
FORCEADD TAP..1
(2750 250);
FORCEPROP 3 LASTPIN (2700 250) SIG_NAME M_C_CPU1_SB_CS_N<1>
J 0
(2710 260);
DISPLAY 0.659574 (2710 260);
PAINT MONO (2710 260);
DISPLAY INVISIBLE (2710 260);
FORCEPROP 1 LASTPIN (2700 250) BN 1
J 0
(2688 258);
DISPLAY 0.680851 (2688 258);
PAINT GREEN (2688 258);
FORCEPROP 2 LAST CDS_LIB standard
J 0
(2750 250);
DISPLAY INVISIBLE (2750 250);
FORCEPROP 1 LAST BODY_TYPE PLUMBING
J 0
(2750 300);
DISPLAY 0.872340 (2750 300);
PAINT GREEN (2750 300);
DISPLAY INVISIBLE (2750 300);
FORCEPROP 1 LAST HDL_TAP TRUE
J 0
(3075 125);
DISPLAY 0.872340 (3075 125);
DISPLAY INVISIBLE (3075 125);
FORCEPROP 1 LAST PATH I93
J 0
(2748 250);
DISPLAY 0.872340 (2748 250);
PAINT GREEN (2748 250);
DISPLAY INVISIBLE (2748 250);
FORCEADD TAP..1
(2750 200);
FORCEPROP 3 LASTPIN (2700 200) SIG_NAME M_C_CPU1_SB_CS_N<0>
J 0
(2710 210);
DISPLAY 0.659574 (2710 210);
PAINT MONO (2710 210);
DISPLAY INVISIBLE (2710 210);
FORCEPROP 1 LASTPIN (2700 200) BN 0
J 0
(2688 208);
DISPLAY 0.680851 (2688 208);
PAINT GREEN (2688 208);
FORCEPROP 2 LAST CDS_LIB standard
J 0
(2750 200);
DISPLAY INVISIBLE (2750 200);
FORCEPROP 1 LAST BODY_TYPE PLUMBING
J 0
(2750 250);
DISPLAY 0.872340 (2750 250);
PAINT GREEN (2750 250);
DISPLAY INVISIBLE (2750 250);
FORCEPROP 1 LAST HDL_TAP TRUE
J 0
(3075 75);
DISPLAY 0.872340 (3075 75);
DISPLAY INVISIBLE (3075 75);
FORCEPROP 1 LAST PATH I94
J 0
(2748 200);
DISPLAY 0.872340 (2748 200);
PAINT GREEN (2748 200);
DISPLAY INVISIBLE (2748 200);
FORCEADD OFFPAGE..4
(3850 -250);
FORCEPROP 2 LAST $XR1 103 
J 0
(4156 -250);
DISPLAY 0.638298 (4156 -250);
PAINT MONO (4156 -250);
FORCEPROP 2 LAST $XR0 102 
J 0
(4036 -250);
DISPLAY 0.638298 (4036 -250);
PAINT MONO (4036 -250);
FORCEPROP 2 LAST CDS_LIB standard
J 0
(3850 -250);
PAINT MONO (3850 -250);
DISPLAY INVISIBLE (3850 -250);
FORCEPROP 1 LAST OFFPAGE TRUE
J 0
(4175 -375);
DISPLAY 1.170213 (4175 -375);
PAINT GREEN (4175 -375);
DISPLAY INVISIBLE (4175 -375);
FORCEPROP 1 LAST COMMENT_BODY TRUE
J 0
(3825 -350);
DISPLAY 1.170213 (3825 -350);
PAINT GREEN (3825 -350);
DISPLAY INVISIBLE (3825 -350);
FORCEPROP 2 LAST PATH I95
J 0
(4025 -175);
DISPLAY 1.021277 (4025 -175);
DISPLAY INVISIBLE (4025 -175);
FORCEADD OFFPAGE..4
(3850 0);
FORCEPROP 2 LAST $XR0 102 
J 0
(4036 0);
DISPLAY 0.638298 (4036 0);
PAINT MONO (4036 0);
FORCEPROP 2 LAST CDS_LIB standard
J 0
(3850 0);
PAINT MONO (3850 0);
DISPLAY INVISIBLE (3850 0);
FORCEPROP 1 LAST OFFPAGE TRUE
J 0
(4175 -125);
DISPLAY 1.170213 (4175 -125);
PAINT GREEN (4175 -125);
DISPLAY INVISIBLE (4175 -125);
FORCEPROP 1 LAST COMMENT_BODY TRUE
J 0
(3825 -100);
DISPLAY 1.170213 (3825 -100);
PAINT GREEN (3825 -100);
DISPLAY INVISIBLE (3825 -100);
FORCEPROP 2 LAST PATH I96
J 0
(4025 75);
DISPLAY 1.021277 (4025 75);
DISPLAY INVISIBLE (4025 75);
FORCEADD OFFPAGE..4
(3850 -100);
FORCEPROP 2 LAST $XR0 103 
J 0
(4036 -100);
DISPLAY 0.638298 (4036 -100);
PAINT MONO (4036 -100);
FORCEPROP 2 LAST CDS_LIB standard
J 0
(3850 -100);
PAINT MONO (3850 -100);
DISPLAY INVISIBLE (3850 -100);
FORCEPROP 1 LAST OFFPAGE TRUE
J 0
(4175 -225);
DISPLAY 1.170213 (4175 -225);
PAINT GREEN (4175 -225);
DISPLAY INVISIBLE (4175 -225);
FORCEPROP 1 LAST COMMENT_BODY TRUE
J 0
(3825 -200);
DISPLAY 1.170213 (3825 -200);
PAINT GREEN (3825 -200);
DISPLAY INVISIBLE (3825 -200);
FORCEPROP 2 LAST PATH I97
J 0
(4025 -25);
DISPLAY 1.021277 (4025 -25);
DISPLAY INVISIBLE (4025 -25);
FORCEADD OFFPAGE..4
(3850 -150);
FORCEPROP 2 LAST $XR0 102 
J 0
(4036 -150);
DISPLAY 0.638298 (4036 -150);
PAINT MONO (4036 -150);
FORCEPROP 2 LAST CDS_LIB standard
J 0
(3850 -150);
PAINT MONO (3850 -150);
DISPLAY INVISIBLE (3850 -150);
FORCEPROP 1 LAST OFFPAGE TRUE
J 0
(4175 -275);
DISPLAY 1.170213 (4175 -275);
PAINT GREEN (4175 -275);
DISPLAY INVISIBLE (4175 -275);
FORCEPROP 1 LAST COMMENT_BODY TRUE
J 0
(3825 -250);
DISPLAY 1.170213 (3825 -250);
PAINT GREEN (3825 -250);
DISPLAY INVISIBLE (3825 -250);
FORCEPROP 2 LAST PATH I98
J 0
(4025 -75);
DISPLAY 1.021277 (4025 -75);
DISPLAY INVISIBLE (4025 -75);
FORCEADD OFFPAGE..4
(3850 50);
FORCEPROP 2 LAST $XR0 103 
J 0
(4036 50);
DISPLAY 0.638298 (4036 50);
PAINT MONO (4036 50);
FORCEPROP 2 LAST CDS_LIB standard
J 0
(3850 50);
PAINT MONO (3850 50);
DISPLAY INVISIBLE (3850 50);
FORCEPROP 1 LAST OFFPAGE TRUE
J 0
(4175 -75);
DISPLAY 1.170213 (4175 -75);
PAINT GREEN (4175 -75);
DISPLAY INVISIBLE (4175 -75);
FORCEPROP 1 LAST COMMENT_BODY TRUE
J 0
(3825 -50);
DISPLAY 1.170213 (3825 -50);
PAINT GREEN (3825 -50);
DISPLAY INVISIBLE (3825 -50);
FORCEPROP 2 LAST PATH I99
J 0
(4025 125);
DISPLAY 1.021277 (4025 125);
DISPLAY INVISIBLE (4025 125);
FORCEADD QUANTA_TITLE_BLOCK_C..1
(5675 -1550);
FORCEPROP 0 LAST CDS_CON_LAST_MODIFIED Fri Aug 25 14:00:35 2023
J 0
(3790 -1535);
PAINT MONO (3790 -1535);
DISPLAY INVISIBLE (3790 -1535);
FORCEPROP 1 LAST CUSTOM_TXT_CDS <CON_LAST_MODIFIED>
J 0
(3790 -1535);
DISPLAY 0.978723 (3790 -1535);
FORCEPROP 2 LAST CUSTOM_TXT_CDS <XR_PAGE_TITLE>
J 0
(-2215 3700);
DISPLAY 0.638298 (-2215 3700);
PAINT PINK (-2215 3700);
DISPLAY INVISIBLE (-2215 3700);
FORCEPROP 2 LAST CUSTOM_TXT_CDS <Q_NUMBER>
J 0
(4272 -1447);
DISPLAY 1.212766 (4272 -1447);
FORCEPROP 2 LAST CUSTOM_TXT_CDS <Q_PROJ>
J 0
(3293 -1448);
DISPLAY 1.212766 (3293 -1448);
FORCEPROP 2 LAST CUSTOM_TXT_CDS <Q_REV>
J 0
(5491 -1447);
DISPLAY 1.212766 (5491 -1447);
FORCEPROP 2 LAST CUSTOM_TXT_CDS <CON_PAGE_NUM> OF <CON_TOTAL_PAGES>
J 0
(5229 -1532);
DISPLAY 0.978723 (5229 -1532);
FORCEPROP 1 LAST CUSTOM_TXT_CDS <NAME_2>
J 0
(2500 -1500);
FORCEPROP 1 LAST CUSTOM_TXT_CDS <NAME_1>
J 0
(2500 -1375);
FORCEPROP 1 LAST Q_TITLE SPR CPU1 - DDR CH C (10 OF 30)
J 0
(-3691 -1524);
DISPLAY 1.957447 (-3691 -1524);
PAINT GREEN (-3691 -1524);
FORCEPROP 1 LAST Q_DEPT 
J 1
(1912 -1501);
DISPLAY 1.957447 (1912 -1501);
PAINT GREEN (1912 -1501);
FORCEPROP 1 LAST COMMENT_BODY TRUE
J 0
(5687 -1563);
DISPLAY 0.978723 (5687 -1563);
PAINT GREEN (5687 -1563);
DISPLAY INVISIBLE (5687 -1563);
FORCEPROP 2 LAST CDS_XR_PAGE_TITLE CR-53 : @S9S_MB_2U_LIB.S9S_MB_2U(SCH_1):PAGE53
J 0
(-2215 3700);
DISPLAY 0.638298 (-2215 3700);
PAINT PINK (-2215 3700);
DISPLAY INVISIBLE (-2215 3700);
FORCEPROP 2 LAST CDS_LIB pure_quanta
J 0
(5675 -1550);
PAINT MONO (5675 -1550);
DISPLAY INVISIBLE (5675 -1550);
FORCEPROP 1 LAST CDS_LMAN_SYM_OUTLINE -9475,6775,100,-125
J 0
(5675 -1550);
DISPLAY 0.468085 (5675 -1550);
PAINT GREEN (5675 -1550);
DISPLAY INVISIBLE (5675 -1550);
FORCEPROP 2 LAST PAGE_BORDER TRUE
J 0
(-2215 3700);
DISPLAY 0.638298 (-2215 3700);
PAINT PINK (-2215 3700);
DISPLAY INVISIBLE (-2215 3700);
WIRE 17 -1 (2800 1675)(3800 1675);
FORCEPROP 2 LAST SIG_NAME M_C_CPU1_SA_CA<6:0>
J 0
(2940 1685);
DISPLAY 0.680851 (2940 1685);
PAINT WHITE (2940 1685);
WIRE 17 -1 (2800 1625)(2800 1675);
WIRE 17 -1 (2800 1575)(2800 1625);
WIRE 17 -1 (2800 1525)(2800 1575);
WIRE 17 -1 (2800 1475)(2800 1525);
WIRE 17 -1 (2800 1425)(2800 1475);
WIRE 17 -1 (2800 1375)(2800 1425);
WIRE 17 -1 (2800 675)(3800 675);
FORCEPROP 2 LAST SIG_NAME M_C_CPU1_SA_CS_N<3:0>
J 0
(2940 685);
DISPLAY 0.680851 (2940 685);
PAINT WHITE (2940 685);
WIRE 17 -1 (2800 625)(2800 675);
WIRE 17 -1 (2800 575)(2800 625);
WIRE 17 -1 (2800 525)(2800 575);
WIRE 17 -1 (2800 3425)(3800 3425);
FORCEPROP 2 LAST SIG_NAME M_C_CPU1_SA_DQS_DN<9:0>
J 0
(2940 3435);
DISPLAY 0.680851 (2940 3435);
PAINT WHITE (2940 3435);
WIRE 17 -1 (2800 3375)(2800 3425);
WIRE 17 -1 (2800 3325)(2800 3375);
WIRE 17 -1 (2800 3275)(2800 3325);
WIRE 17 -1 (2800 3225)(2800 3275);
WIRE 17 -1 (2800 3175)(2800 3225);
WIRE 17 -1 (2800 3125)(2800 3175);
WIRE 17 -1 (2800 3075)(2800 3125);
WIRE 17 -1 (2800 3025)(2800 3075);
WIRE 17 -1 (2800 2975)(2800 3025);
WIRE 17 -1 (2800 3975)(3800 3975);
FORCEPROP 2 LAST SIG_NAME M_C_CPU1_SA_DQS_DP<9:0>
J 0
(2940 3985);
DISPLAY 0.680851 (2940 3985);
PAINT WHITE (2940 3985);
WIRE 17 -1 (2800 3925)(2800 3975);
WIRE 17 -1 (2800 3875)(2800 3925);
WIRE 17 -1 (2800 3825)(2800 3875);
WIRE 17 -1 (2800 3775)(2800 3825);
WIRE 17 -1 (2800 3725)(2800 3775);
WIRE 17 -1 (2800 3675)(2800 3725);
WIRE 17 -1 (2800 3625)(2800 3675);
WIRE 17 -1 (2800 3575)(2800 3625);
WIRE 17 -1 (2800 3525)(2800 3575);
WIRE 17 -1 (2800 1175)(3800 1175);
FORCEPROP 2 LAST SIG_NAME M_C_CPU1_SB_CA<6:0>
J 0
(2940 1185);
DISPLAY 0.680851 (2940 1185);
PAINT WHITE (2940 1185);
WIRE 17 -1 (2800 1125)(2800 1175);
WIRE 17 -1 (2800 1075)(2800 1125);
WIRE 17 -1 (2800 1025)(2800 1075);
WIRE 17 -1 (2800 975)(2800 1025);
WIRE 17 -1 (2800 925)(2800 975);
WIRE 17 -1 (2800 875)(2800 925);
WIRE 17 -1 (2800 375)(3800 375);
FORCEPROP 2 LAST SIG_NAME M_C_CPU1_SB_CS_N<3:0>
J 0
(2940 385);
DISPLAY 0.680851 (2940 385);
PAINT WHITE (2940 385);
WIRE 17 -1 (2800 325)(2800 375);
WIRE 17 -1 (2800 275)(2800 325);
WIRE 17 -1 (2800 225)(2800 275);
WIRE 17 -1 (2800 2275)(3800 2275);
FORCEPROP 2 LAST SIG_NAME M_C_CPU1_SB_DQS_DN<9:0>
J 0
(2940 2285);
DISPLAY 0.680851 (2940 2285);
PAINT WHITE (2940 2285);
WIRE 17 -1 (2800 2225)(2800 2275);
WIRE 17 -1 (2800 2175)(2800 2225);
WIRE 17 -1 (2800 2125)(2800 2175);
WIRE 17 -1 (2800 2075)(2800 2125);
WIRE 17 -1 (2800 2025)(2800 2075);
WIRE 17 -1 (2800 1975)(2800 2025);
WIRE 17 -1 (2800 1925)(2800 1975);
WIRE 17 -1 (2800 1875)(2800 1925);
WIRE 17 -1 (2800 1825)(2800 1875);
WIRE 17 -1 (2800 2825)(3800 2825);
FORCEPROP 2 LAST SIG_NAME M_C_CPU1_SB_DQS_DP<9:0>
J 0
(2940 2835);
DISPLAY 0.680851 (2940 2835);
PAINT WHITE (2940 2835);
WIRE 17 -1 (2800 2775)(2800 2825);
WIRE 17 -1 (2800 2725)(2800 2775);
WIRE 17 -1 (2800 2675)(2800 2725);
WIRE 17 -1 (2800 2625)(2800 2675);
WIRE 17 -1 (2800 2575)(2800 2625);
WIRE 17 -1 (2800 2525)(2800 2575);
WIRE 17 -1 (2800 2475)(2800 2525);
WIRE 17 -1 (2800 2425)(2800 2475);
WIRE 17 -1 (2800 2375)(2800 2425);
WIRE 17 -1 (-725 25)(-725 75);
WIRE 17 -1 (-725 75)(-725 125);
WIRE 17 -1 (-725 125)(-725 175);
WIRE 17 -1 (-725 175)(-725 225);
WIRE 17 -1 (-725 225)(-725 275);
WIRE 17 -1 (-725 275)(-725 325);
WIRE 17 -1 (-725 325)(-725 375);
WIRE 17 -1 (-1650 375)(-725 375);
FORCEPROP 2 LAST SIG_NAME M_C_CPU1_SB_CB<7:0>
J 0
(-1510 385);
DISPLAY 0.680851 (-1510 385);
PAINT WHITE (-1510 385);
WIRE 17 -1 (-725 425)(-725 475);
WIRE 17 -1 (-725 475)(-725 525);
WIRE 17 -1 (-725 525)(-725 575);
WIRE 17 -1 (-725 575)(-725 625);
WIRE 17 -1 (-725 625)(-725 675);
WIRE 17 -1 (-725 675)(-725 725);
WIRE 17 -1 (-725 725)(-725 775);
WIRE 17 -1 (-725 775)(-725 825);
WIRE 17 -1 (-725 825)(-725 875);
WIRE 17 -1 (-725 875)(-725 925);
WIRE 17 -1 (-725 925)(-725 975);
WIRE 17 -1 (-725 975)(-725 1025);
WIRE 17 -1 (-725 1025)(-725 1075);
WIRE 17 -1 (-725 1075)(-725 1125);
WIRE 17 -1 (-725 1125)(-725 1175);
WIRE 17 -1 (-725 1175)(-725 1225);
WIRE 17 -1 (-725 1225)(-725 1275);
WIRE 17 -1 (-725 1275)(-725 1325);
WIRE 17 -1 (-725 1325)(-725 1375);
WIRE 17 -1 (-725 1375)(-725 1425);
WIRE 17 -1 (-725 1425)(-725 1475);
WIRE 17 -1 (-725 1475)(-725 1525);
WIRE 17 -1 (-725 1525)(-725 1575);
WIRE 17 -1 (-725 1575)(-725 1625);
WIRE 17 -1 (-725 1625)(-725 1675);
WIRE 17 -1 (-725 1675)(-725 1725);
WIRE 17 -1 (-725 1725)(-725 1775);
WIRE 17 -1 (-725 1775)(-725 1825);
WIRE 17 -1 (-725 1825)(-725 1875);
WIRE 17 -1 (-725 1875)(-725 1925);
WIRE 17 -1 (-725 1925)(-725 1975);
WIRE 17 -1 (-1650 1975)(-725 1975);
FORCEPROP 2 LAST SIG_NAME M_C_CPU1_SB_DQ<31:0>
J 0
(-1510 1985);
DISPLAY 0.680851 (-1510 1985);
PAINT WHITE (-1510 1985);
WIRE 17 -1 (-725 2025)(-725 2075);
WIRE 17 -1 (-725 2075)(-725 2125);
WIRE 17 -1 (-725 2125)(-725 2175);
WIRE 17 -1 (-725 2175)(-725 2225);
WIRE 17 -1 (-725 2225)(-725 2275);
WIRE 17 -1 (-725 2275)(-725 2325);
WIRE 17 -1 (-725 2325)(-725 2375);
WIRE 17 -1 (-1650 2375)(-725 2375);
FORCEPROP 2 LAST SIG_NAME M_C_CPU1_SA_CB<7:0>
J 0
(-1510 2385);
DISPLAY 0.680851 (-1510 2385);
PAINT WHITE (-1510 2385);
WIRE 17 -1 (-725 2425)(-725 2475);
WIRE 17 -1 (-725 2475)(-725 2525);
WIRE 17 -1 (-725 2525)(-725 2575);
WIRE 17 -1 (-725 2575)(-725 2625);
WIRE 17 -1 (-725 2625)(-725 2675);
WIRE 17 -1 (-725 2675)(-725 2725);
WIRE 17 -1 (-725 2725)(-725 2775);
WIRE 17 -1 (-725 2775)(-725 2825);
WIRE 17 -1 (-725 2825)(-725 2875);
WIRE 17 -1 (-725 2875)(-725 2925);
WIRE 17 -1 (-725 2925)(-725 2975);
WIRE 17 -1 (-725 2975)(-725 3025);
WIRE 17 -1 (-725 3025)(-725 3075);
WIRE 17 -1 (-725 3075)(-725 3125);
WIRE 17 -1 (-725 3125)(-725 3175);
WIRE 17 -1 (-725 3175)(-725 3225);
WIRE 17 -1 (-725 3225)(-725 3275);
WIRE 17 -1 (-725 3275)(-725 3325);
WIRE 17 -1 (-725 3325)(-725 3375);
WIRE 17 -1 (-725 3375)(-725 3425);
WIRE 17 -1 (-725 3425)(-725 3475);
WIRE 17 -1 (-725 3475)(-725 3525);
WIRE 17 -1 (-725 3525)(-725 3575);
WIRE 17 -1 (-725 3575)(-725 3625);
WIRE 17 -1 (-725 3625)(-725 3675);
WIRE 17 -1 (-725 3675)(-725 3725);
WIRE 17 -1 (-725 3725)(-725 3775);
WIRE 17 -1 (-725 3775)(-725 3825);
WIRE 17 -1 (-725 3825)(-725 3875);
WIRE 17 -1 (-725 3875)(-725 3925);
WIRE 17 -1 (-725 3925)(-725 3975);
WIRE 17 -1 (-1650 3975)(-725 3975);
FORCEPROP 2 LAST SIG_NAME M_C_CPU1_SA_DQ<31:0>
J 0
(-1510 3985);
DISPLAY 0.680851 (-1510 3985);
PAINT WHITE (-1510 3985);
WIRE 17 -1 (-725 -125)(-725 -75);
WIRE 17 -1 (-1650 -75)(-725 -75);
FORCEPROP 2 LAST SIG_NAME M_C_CPU1_CLK_DP<1:0>
J 0
(-1510 -65);
DISPLAY 0.680851 (-1510 -65);
PAINT WHITE (-1510 -65);
WIRE 17 -1 (-725 -225)(-725 -175);
WIRE 17 -1 (-1650 -175)(-725 -175);
FORCEPROP 2 LAST SIG_NAME M_C_CPU1_CLK_DN<1:0>
J 0
(-1510 -165);
DISPLAY 0.680851 (-1510 -165);
PAINT WHITE (-1510 -165);
WIRE 16 -1 (-625 -200)(-175 -200);
WIRE 16 -1 (-625 -250)(-175 -250);
WIRE 16 -1 (-625 -100)(-175 -100);
WIRE 16 -1 (-625 -150)(-175 -150);
WIRE 16 -1 (-625 3950)(-175 3950);
WIRE 16 -1 (-625 3900)(-175 3900);
WIRE 16 -1 (-625 3850)(-175 3850);
WIRE 16 -1 (-625 3800)(-175 3800);
WIRE 16 -1 (-625 3750)(-175 3750);
WIRE 16 -1 (-625 3700)(-175 3700);
WIRE 16 -1 (-625 3650)(-175 3650);
WIRE 16 -1 (-625 3600)(-175 3600);
WIRE 16 -1 (-625 3550)(-175 3550);
WIRE 16 -1 (-625 3500)(-175 3500);
WIRE 16 -1 (-625 3450)(-175 3450);
WIRE 16 -1 (-625 3400)(-175 3400);
WIRE 16 -1 (-625 3350)(-175 3350);
WIRE 16 -1 (-625 3300)(-175 3300);
WIRE 16 -1 (-625 3250)(-175 3250);
WIRE 16 -1 (-625 3200)(-175 3200);
WIRE 16 -1 (-625 3150)(-175 3150);
WIRE 16 -1 (-625 3100)(-175 3100);
WIRE 16 -1 (-625 3050)(-175 3050);
WIRE 16 -1 (-625 3000)(-175 3000);
WIRE 16 -1 (-625 2950)(-175 2950);
WIRE 16 -1 (-625 2900)(-175 2900);
WIRE 16 -1 (-625 2850)(-175 2850);
WIRE 16 -1 (-625 2800)(-175 2800);
WIRE 16 -1 (-625 2750)(-175 2750);
WIRE 16 -1 (-625 2700)(-175 2700);
WIRE 16 -1 (-625 2650)(-175 2650);
WIRE 16 -1 (-625 2600)(-175 2600);
WIRE 16 -1 (-625 2550)(-175 2550);
WIRE 16 -1 (-625 2500)(-175 2500);
WIRE 16 -1 (-625 2450)(-175 2450);
WIRE 16 -1 (-625 2400)(-175 2400);
WIRE 16 -1 (-625 2350)(-175 2350);
WIRE 16 -1 (-625 2300)(-175 2300);
WIRE 16 -1 (-625 2250)(-175 2250);
WIRE 16 -1 (-625 2200)(-175 2200);
WIRE 16 -1 (-625 2150)(-175 2150);
WIRE 16 -1 (-625 2100)(-175 2100);
WIRE 16 -1 (-625 2050)(-175 2050);
WIRE 16 -1 (-625 2000)(-175 2000);
WIRE 16 -1 (-625 1950)(-175 1950);
WIRE 16 -1 (-625 1900)(-175 1900);
WIRE 16 -1 (-625 1850)(-175 1850);
WIRE 16 -1 (-625 1800)(-175 1800);
WIRE 16 -1 (-625 1750)(-175 1750);
WIRE 16 -1 (-625 1700)(-175 1700);
WIRE 16 -1 (-625 1650)(-175 1650);
WIRE 16 -1 (-625 1600)(-175 1600);
WIRE 16 -1 (-625 1550)(-175 1550);
WIRE 16 -1 (-625 1500)(-175 1500);
WIRE 16 -1 (-625 1450)(-175 1450);
WIRE 16 -1 (-625 1400)(-175 1400);
WIRE 16 -1 (-625 1350)(-175 1350);
WIRE 16 -1 (-625 1300)(-175 1300);
WIRE 16 -1 (-625 1250)(-175 1250);
WIRE 16 -1 (-625 1200)(-175 1200);
WIRE 16 -1 (-625 1150)(-175 1150);
WIRE 16 -1 (-625 1100)(-175 1100);
WIRE 16 -1 (-625 1050)(-175 1050);
WIRE 16 -1 (-625 1000)(-175 1000);
WIRE 16 -1 (-625 950)(-175 950);
WIRE 16 -1 (-625 900)(-175 900);
WIRE 16 -1 (-625 850)(-175 850);
WIRE 16 -1 (-625 800)(-175 800);
WIRE 16 -1 (-625 750)(-175 750);
WIRE 16 -1 (-625 700)(-175 700);
WIRE 16 -1 (-625 650)(-175 650);
WIRE 16 -1 (-625 600)(-175 600);
WIRE 16 -1 (-625 550)(-175 550);
WIRE 16 -1 (-625 500)(-175 500);
WIRE 16 -1 (-625 450)(-175 450);
WIRE 16 -1 (-625 400)(-175 400);
WIRE 16 -1 (-625 350)(-175 350);
WIRE 16 -1 (-625 300)(-175 300);
WIRE 16 -1 (-625 250)(-175 250);
WIRE 16 -1 (-625 200)(-175 200);
WIRE 16 -1 (-625 150)(-175 150);
WIRE 16 -1 (-625 100)(-175 100);
WIRE 16 -1 (-625 50)(-175 50);
WIRE 16 -1 (-625 0)(-175 0);
WIRE 16 -1 (3800 800)(2275 800);
FORCEPROP 2 LAST SIG_NAME M_C_CPU1_SB_PAR
J 0
(2909 809);
DISPLAY 0.680851 (2909 809);
PAINT WHITE (2909 809);
WIRE 16 -1 (2275 2350)(2700 2350);
WIRE 16 -1 (2275 2400)(2700 2400);
WIRE 16 -1 (2275 2450)(2700 2450);
WIRE 16 -1 (2275 2500)(2700 2500);
WIRE 16 -1 (2275 2550)(2700 2550);
WIRE 16 -1 (2275 2600)(2700 2600);
WIRE 16 -1 (2275 2650)(2700 2650);
WIRE 16 -1 (2275 2700)(2700 2700);
WIRE 16 -1 (2275 2750)(2700 2750);
WIRE 16 -1 (2275 2800)(2700 2800);
WIRE 16 -1 (2275 1800)(2700 1800);
WIRE 16 -1 (2275 1850)(2700 1850);
WIRE 16 -1 (2275 1900)(2700 1900);
WIRE 16 -1 (2275 1950)(2700 1950);
WIRE 16 -1 (2275 2000)(2700 2000);
WIRE 16 -1 (2275 2050)(2700 2050);
WIRE 16 -1 (2275 2100)(2700 2100);
WIRE 16 -1 (2275 2150)(2700 2150);
WIRE 16 -1 (2275 2200)(2700 2200);
WIRE 16 -1 (2275 2250)(2700 2250);
WIRE 16 -1 (2275 200)(2700 200);
WIRE 16 -1 (2275 250)(2700 250);
WIRE 16 -1 (2275 300)(2700 300);
WIRE 16 -1 (2275 350)(2700 350);
WIRE 16 -1 (2275 850)(2700 850);
WIRE 16 -1 (2275 900)(2700 900);
WIRE 16 -1 (2275 950)(2700 950);
WIRE 16 -1 (2275 1000)(2700 1000);
WIRE 16 -1 (2275 1050)(2700 1050);
WIRE 16 -1 (2275 1100)(2700 1100);
WIRE 16 -1 (2275 1150)(2700 1150);
WIRE 16 -1 (3800 1300)(2275 1300);
FORCEPROP 2 LAST SIG_NAME M_C_CPU1_SA_PAR
J 0
(2909 1309);
DISPLAY 0.680851 (2909 1309);
PAINT WHITE (2909 1309);
WIRE 16 -1 (2275 3500)(2700 3500);
WIRE 16 -1 (2275 3550)(2700 3550);
WIRE 16 -1 (2275 3600)(2700 3600);
WIRE 16 -1 (2275 3650)(2700 3650);
WIRE 16 -1 (2275 3700)(2700 3700);
WIRE 16 -1 (2275 3750)(2700 3750);
WIRE 16 -1 (2275 3800)(2700 3800);
WIRE 16 -1 (2275 3850)(2700 3850);
WIRE 16 -1 (2275 3900)(2700 3900);
WIRE 16 -1 (2275 3950)(2700 3950);
WIRE 16 -1 (2275 2950)(2700 2950);
WIRE 16 -1 (2275 3000)(2700 3000);
WIRE 16 -1 (2275 3050)(2700 3050);
WIRE 16 -1 (2275 3100)(2700 3100);
WIRE 16 -1 (2275 3150)(2700 3150);
WIRE 16 -1 (2275 3200)(2700 3200);
WIRE 16 -1 (2275 3250)(2700 3250);
WIRE 16 -1 (2275 3300)(2700 3300);
WIRE 16 -1 (2275 3350)(2700 3350);
WIRE 16 -1 (2275 3400)(2700 3400);
WIRE 16 -1 (2275 500)(2700 500);
WIRE 16 -1 (2275 550)(2700 550);
WIRE 16 -1 (2275 600)(2700 600);
WIRE 16 -1 (2275 650)(2700 650);
WIRE 16 -1 (2275 1350)(2700 1350);
WIRE 16 -1 (2275 1400)(2700 1400);
WIRE 16 -1 (2275 1450)(2700 1450);
WIRE 16 -1 (2275 1500)(2700 1500);
WIRE 16 -1 (2275 1550)(2700 1550);
WIRE 16 -1 (2275 1600)(2700 1600);
WIRE 16 -1 (2275 1650)(2700 1650);
WIRE 16 -1 (3800 -150)(2275 -150);
FORCEPROP 2 LAST SIG_NAME M_C_CPU1_SB_RSP<0>
J 0
(2909 -141);
DISPLAY 0.680851 (2909 -141);
PAINT WHITE (2909 -141);
WIRE 16 -1 (3800 -100)(2275 -100);
FORCEPROP 2 LAST SIG_NAME M_C_CPU1_SB_RSP<1>
J 0
(2909 -91);
DISPLAY 0.680851 (2909 -91);
PAINT WHITE (2909 -91);
WIRE 16 -1 (3800 0)(2275 0);
FORCEPROP 2 LAST SIG_NAME M_C_CPU1_SA_RSP<0>
J 0
(2909 9);
DISPLAY 0.680851 (2909 9);
PAINT WHITE (2909 9);
WIRE 16 -1 (3800 50)(2275 50);
FORCEPROP 2 LAST SIG_NAME M_C_CPU1_SA_RSP<1>
J 0
(2909 59);
DISPLAY 0.680851 (2909 59);
PAINT WHITE (2909 59);
WIRE 16 -1 (3800 -250)(2275 -250);
FORCEPROP 2 LAST SIG_NAME M_C_CPU1_ALERT_N
J 0
(2909 -241);
DISPLAY 0.680851 (2909 -241);
PAINT WHITE (2909 -241);
QUIT
